FILE_TYPE = MACRO_DRAWING;
SET COLOR_WIRE YELLOW;
SET COLOR_PROP ORANGE;
SET COLOR_DOT WHITE;
SET COLOR_ARC YELLOW;
SET COLOR_BODY GREEN;
SET COLOR_NOTE PURPLE;
SET PROP_DISPLAY VALUE;
SET PAGE_NUMBER P342;
FORCEADD OFFPAGE..1
(3075 -3175);
FORCEPROP 2 LAST $XR2 138 
J 0
(2583 -3175);
DISPLAY 0.638298 (2583 -3175);
PAINT MONO (2583 -3175);
FORCEPROP 2 LAST $XR1 142 
J 0
(2703 -3175);
DISPLAY 0.638298 (2703 -3175);
PAINT MONO (2703 -3175);
FORCEPROP 2 LAST $XR0 137 
J 0
(2823 -3175);
DISPLAY 0.638298 (2823 -3175);
PAINT MONO (2823 -3175);
FORCEPROP 2 LAST CDS_LIB standard
J 0
(3075 -3175);
PAINT MONO (3075 -3175);
DISPLAY INVISIBLE (3075 -3175);
FORCEPROP 1 LAST OFFPAGE TRUE
J 0
(3400 -3300);
DISPLAY 0.872340 (3400 -3300);
PAINT GREEN (3400 -3300);
DISPLAY INVISIBLE (3400 -3300);
FORCEPROP 1 LAST COMMENT_BODY TRUE
J 0
(3200 -3275);
DISPLAY 0.872340 (3200 -3275);
PAINT GREEN (3200 -3275);
DISPLAY INVISIBLE (3200 -3275);
FORCEPROP 2 LAST PATH I1
J 0
(2825 -3125);
DISPLAY 0.680851 (2825 -3125);
DISPLAY INVISIBLE (2825 -3125);
FORCEADD UNIVERSAL_GND..1
(5875 -3500);
FORCEPROP 3 LASTPIN (5875 -3450) SIG_NAME GND\g
J 0
(5885 -3440);
DISPLAY 0.659574 (5885 -3440);
PAINT MONO (5885 -3440);
DISPLAY INVISIBLE (5885 -3440);
FORCEPROP 2 LAST CDS_LIB pure_quanta_power
J 0
(5875 -3500);
PAINT MONO (5875 -3500);
DISPLAY INVISIBLE (5875 -3500);
FORCEPROP 1 LAST HDL_POWER GND
J 1
(5900 -3575);
DISPLAY 0.872340 (5900 -3575);
PAINT GREEN (5900 -3575);
DISPLAY INVISIBLE (5900 -3575);
FORCEPROP 1 LAST PATH I10
J 0
(5950 -3500);
DISPLAY 0.872340 (5950 -3500);
PAINT AQUA (5950 -3500);
DISPLAY INVISIBLE (5950 -3500);
FORCEADD UNIVERSAL_GND..1
(5650 -2925);
FORCEPROP 3 LASTPIN (5650 -2875) SIG_NAME GND\g
J 0
(5660 -2865);
DISPLAY 0.659574 (5660 -2865);
PAINT MONO (5660 -2865);
DISPLAY INVISIBLE (5660 -2865);
FORCEPROP 2 LAST CDS_LIB pure_quanta_power
J 0
(5650 -2925);
PAINT MONO (5650 -2925);
DISPLAY INVISIBLE (5650 -2925);
FORCEPROP 1 LAST HDL_POWER GND
J 1
(5675 -3000);
DISPLAY 0.872340 (5675 -3000);
PAINT GREEN (5675 -3000);
DISPLAY INVISIBLE (5675 -3000);
FORCEPROP 1 LAST PATH I11
J 0
(5725 -2925);
DISPLAY 0.872340 (5725 -2925);
PAINT AQUA (5725 -2925);
DISPLAY INVISIBLE (5725 -2925);
FORCEADD Q_CAP..1
R 2
(5650 -2700);
FORCEPROP 1 LAST LOCATION C1841
J 2
(5600 -2600);
DISPLAY 0.978723 (5600 -2600);
FORCEPROP 2 LAST $SEC 1
J 0
(5600 -2500);
DISPLAY 0.680851 (5600 -2500);
PAINT MONO (5600 -2500);
DISPLAY INVISIBLE (5600 -2500);
FORCEPROP 2 LAST CDS_SEC 1
J 0
(5600 -2500);
DISPLAY 1.021277 (5600 -2500);
DISPLAY INVISIBLE (5600 -2500);
FORCEPROP 1 LASTPIN (5650 -2600) $PN 1
J 2
(5640 -2620);
DISPLAY 0.787234 (5640 -2620);
FORCEPROP 1 LASTPIN (5650 -2800) $PN 2
J 2
(5640 -2820);
DISPLAY 0.787234 (5640 -2820);
FORCEPROP 1 LAST VALUE 0.1UF
J 2
(5600 -2650);
DISPLAY 0.510638 (5600 -2650);
FORCEPROP 1 LAST VOLTAGE 25V
J 2
(5600 -2700);
DISPLAY 0.510638 (5600 -2700);
FORCEPROP 1 LAST MATERIAL X7R
J 2
(5600 -2800);
DISPLAY 0.510638 (5600 -2800);
FORCEPROP 1 LAST PACK_TYPE 0402
J 2
(5600 -2900);
DISPLAY 0.510638 (5600 -2900);
FORCEPROP 1 LAST TOLERANCE 10%
J 2
(5600 -2750);
DISPLAY 0.510638 (5600 -2750);
FORCEPROP 2 LAST CDS_LIB pure_quanta
J 0
(5650 -2700);
PAINT MONO (5650 -2700);
DISPLAY INVISIBLE (5650 -2700);
FORCEPROP 1 LAST PATH I12
J 2
(5600 -2550);
DISPLAY 0.978723 (5600 -2550);
PAINT WHITE (5600 -2550);
DISPLAY INVISIBLE (5600 -2550);
FORCEPROP 1 LAST PART_NUMBER CH4104K1B00
J 2
(5600 -2850);
DISPLAY 0.510638 (5600 -2850);
DISPLAY INVISIBLE (5600 -2850);
FORCEADD UNIVERSAL_POWER..1
(5650 -2400);
FORCEPROP 3 LASTPIN (5650 -2450) SIG_NAME P3V3_AUX\g
J 0
(5660 -2440);
DISPLAY 0.659574 (5660 -2440);
PAINT MONO (5660 -2440);
DISPLAY INVISIBLE (5660 -2440);
FORCEPROP 1 LAST HDL_POWER P3V3_AUX
J 1
(5650 -2350);
DISPLAY 0.872340 (5650 -2350);
PAINT GREEN (5650 -2350);
FORCEPROP 2 LAST CDS_LIB pure_quanta_power
J 0
(5650 -2400);
PAINT MONO (5650 -2400);
DISPLAY INVISIBLE (5650 -2400);
FORCEPROP 1 LAST PATH I13
J 0
(5700 -2375);
DISPLAY 0.872340 (5700 -2375);
PAINT AQUA (5700 -2375);
DISPLAY INVISIBLE (5700 -2375);
FORCEADD 74LVC1G126SE7..1
(4850 -1725);
FORCEPROP 1 LAST LOCATION U217
J 0
(4956 -1894);
DISPLAY 0.723404 (4956 -1894);
PAINT GREEN (4956 -1894);
FORCEPROP 0 LAST $SEC 1
J 0
(4975 -1500);
DISPLAY 0.680851 (4975 -1500);
PAINT MONO (4975 -1500);
DISPLAY INVISIBLE (4975 -1500);
FORCEPROP 0 LAST CDS_SEC 1
J 0
(4975 -1500);
DISPLAY 1.021277 (4975 -1500);
DISPLAY INVISIBLE (4975 -1500);
FORCEPROP 0 LASTPIN (4600 -1675) $PN 2
J 2
(4590 -1665);
DISPLAY 0.680851 (4590 -1665);
PAINT MONO (4590 -1665);
FORCEPROP 0 LASTPIN (4850 -1975) $PN 3
R 1
J 2
(4840 -1985);
DISPLAY 0.680851 (4840 -1985);
PAINT MONO (4840 -1985);
FORCEPROP 0 LASTPIN (4600 -1775) $PN 1
J 2
(4590 -1765);
DISPLAY 0.680851 (4590 -1765);
PAINT MONO (4590 -1765);
FORCEPROP 0 LASTPIN (4850 -1475) $PN 5
R 1
J 0
(4840 -1465);
DISPLAY 0.680851 (4840 -1465);
PAINT MONO (4840 -1465);
FORCEPROP 0 LASTPIN (5100 -1725) $PN 4
J 0
(5110 -1715);
DISPLAY 0.680851 (5110 -1715);
PAINT MONO (5110 -1715);
FORCEPROP 1 LAST MATERIAL IC
J 0
(4925 -2075);
DISPLAY 0.723404 (4925 -2075);
PAINT GREEN (4925 -2075);
FORCEPROP 2 LAST VALUE 74LVC1G126SE-7
J 0
(4875 -1575);
DISPLAY 0.638298 (4875 -1575);
FORCEPROP 2 LAST PART_TYPE SMLF
J 0
(4975 -1550);
DISPLAY 0.638298 (4975 -1550);
FORCEPROP 2 LAST CDS_LIB pure_quanta
J 0
(4850 -1725);
DISPLAY INVISIBLE (4850 -1725);
FORCEPROP 1 LAST CDS_LMAN_SYM_OUTLINE -100,100,100,-100
J 0
(4850 -1725);
DISPLAY 0.468085 (4850 -1725);
PAINT GREEN (4850 -1725);
DISPLAY INVISIBLE (4850 -1725);
FORCEPROP 1 LAST NEEDS_NO_SIZE TRUE
J 0
(4850 -1725);
DISPLAY 0.723404 (4850 -1725);
PAINT GREEN (4850 -1725);
DISPLAY INVISIBLE (4850 -1725);
FORCEPROP 1 LAST PATH I14
J 0
(4850 -1725);
DISPLAY 0.723404 (4850 -1725);
PAINT GREEN (4850 -1725);
DISPLAY INVISIBLE (4850 -1725);
FORCEPROP 1 LAST PART_NUMBER AL1G0126009
J 0
(4931 -2016);
DISPLAY 0.723404 (4931 -2016);
PAINT GREEN (4931 -2016);
DISPLAY INVISIBLE (4931 -2016);
FORCEADD OFFPAGE..1
(4325 -400);
FORCEPROP 2 LAST $XR2 133 
J 0
(3864 -400);
DISPLAY 0.638298 (3864 -400);
PAINT MONO (3864 -400);
FORCEPROP 2 LAST $XR1 83 
J 0
(3984 -400);
DISPLAY 0.638298 (3984 -400);
PAINT MONO (3984 -400);
FORCEPROP 2 LAST $XR0 80 
J 0
(4074 -400);
DISPLAY 0.638298 (4074 -400);
PAINT MONO (4074 -400);
FORCEPROP 2 LAST CDS_LIB standard
J 0
(4325 -400);
PAINT MONO (4325 -400);
DISPLAY INVISIBLE (4325 -400);
FORCEPROP 1 LAST OFFPAGE TRUE
J 0
(4650 -525);
DISPLAY 0.872340 (4650 -525);
PAINT GREEN (4650 -525);
DISPLAY INVISIBLE (4650 -525);
FORCEPROP 1 LAST COMMENT_BODY TRUE
J 0
(4450 -500);
DISPLAY 0.872340 (4450 -500);
PAINT GREEN (4450 -500);
DISPLAY INVISIBLE (4450 -500);
FORCEPROP 2 LAST PATH I15
J 0
(4075 -350);
DISPLAY 0.680851 (4075 -350);
DISPLAY INVISIBLE (4075 -350);
FORCEADD Q_CAP..1
(5150 -1225);
FORCEPROP 1 LAST LOCATION C1822
J 0
(5200 -1125);
DISPLAY 0.978723 (5200 -1125);
FORCEPROP 2 LAST $SEC 1
J 0
(5200 -1025);
DISPLAY 0.680851 (5200 -1025);
PAINT MONO (5200 -1025);
DISPLAY INVISIBLE (5200 -1025);
FORCEPROP 2 LAST CDS_SEC 1
J 0
(5200 -1025);
DISPLAY 1.021277 (5200 -1025);
DISPLAY INVISIBLE (5200 -1025);
FORCEPROP 1 LASTPIN (5150 -1125) $PN 1
J 0
(5160 -1145);
DISPLAY 0.787234 (5160 -1145);
FORCEPROP 1 LASTPIN (5150 -1325) $PN 2
J 0
(5160 -1345);
DISPLAY 0.787234 (5160 -1345);
FORCEPROP 1 LAST VOLTAGE 25V
J 0
(5200 -1225);
DISPLAY 0.510638 (5200 -1225);
FORCEPROP 1 LAST PACK_TYPE 0402
J 0
(5200 -1425);
DISPLAY 0.510638 (5200 -1425);
FORCEPROP 1 LAST MATERIAL X7R
J 0
(5200 -1325);
DISPLAY 0.510638 (5200 -1325);
FORCEPROP 1 LAST TOLERANCE 10%
J 0
(5200 -1275);
DISPLAY 0.510638 (5200 -1275);
FORCEPROP 1 LAST VALUE 0.1UF
J 0
(5200 -1175);
DISPLAY 0.510638 (5200 -1175);
FORCEPROP 2 LAST CDS_LIB pure_quanta
J 2
(5150 -1225);
PAINT MONO (5150 -1225);
DISPLAY INVISIBLE (5150 -1225);
FORCEPROP 1 LAST PATH I16
J 0
(5200 -1075);
DISPLAY 0.978723 (5200 -1075);
PAINT WHITE (5200 -1075);
DISPLAY INVISIBLE (5200 -1075);
FORCEPROP 1 LAST PART_NUMBER CH4104K1B00
J 0
(5200 -1375);
DISPLAY 0.510638 (5200 -1375);
DISPLAY INVISIBLE (5200 -1375);
FORCEADD UNIVERSAL_GND..1
(5150 -1450);
FORCEPROP 3 LASTPIN (5150 -1400) SIG_NAME GND\g
J 0
(5160 -1390);
DISPLAY 0.659574 (5160 -1390);
PAINT MONO (5160 -1390);
DISPLAY INVISIBLE (5160 -1390);
FORCEPROP 2 LAST CDS_LIB pure_quanta_power
J 0
(5150 -1450);
PAINT MONO (5150 -1450);
DISPLAY INVISIBLE (5150 -1450);
FORCEPROP 1 LAST HDL_POWER GND
J 1
(5175 -1525);
DISPLAY 0.872340 (5175 -1525);
PAINT GREEN (5175 -1525);
DISPLAY INVISIBLE (5175 -1525);
FORCEPROP 1 LAST PATH I17
J 0
(5225 -1450);
DISPLAY 0.872340 (5225 -1450);
PAINT AQUA (5225 -1450);
DISPLAY INVISIBLE (5225 -1450);
FORCEADD Q_RES..2
(5975 -1275);
FORCEPROP 1 LAST LOCATION R3184
J 0
(6020 -1150);
DISPLAY 0.978723 (6020 -1150);
FORCEPROP 0 LAST $SEC 1
J 0
(6025 -1100);
DISPLAY 0.680851 (6025 -1100);
PAINT MONO (6025 -1100);
DISPLAY INVISIBLE (6025 -1100);
FORCEPROP 0 LAST CDS_SEC 1
J 0
(6025 -1100);
DISPLAY 1.021277 (6025 -1100);
DISPLAY INVISIBLE (6025 -1100);
FORCEPROP 1 LASTPIN (5975 -1175) $PN 1
J 0
(5980 -1213);
DISPLAY 0.787234 (5980 -1213);
PAINT MONO (5980 -1213);
FORCEPROP 1 LASTPIN (5975 -1375) $PN 2
J 0
(5980 -1365);
DISPLAY 0.787234 (5980 -1365);
PAINT MONO (5980 -1365);
FORCEPROP 1 LAST MATERIAL CHIP
J 0
(6015 -1350);
DISPLAY 0.787234 (6015 -1350);
FORCEPROP 1 LAST WATTAGE 1/16W
J 0
(6015 -1300);
DISPLAY 0.787234 (6015 -1300);
FORCEPROP 1 LAST TOLERANCE 1%
J 0
(6020 -1250);
DISPLAY 0.787234 (6020 -1250);
FORCEPROP 1 LAST PACK_TYPE 0402LF
J 0
(6015 -1450);
DISPLAY 0.787234 (6015 -1450);
FORCEPROP 1 LAST VALUE 4.7K
J 0
(6020 -1200);
DISPLAY 0.787234 (6020 -1200);
FORCEPROP 2 LAST CDS_LIB pure_quanta
J 0
(5975 -1275);
DISPLAY INVISIBLE (5975 -1275);
FORCEPROP 1 LAST PATH I18
J 0
(6025 -1100);
DISPLAY 0.978723 (6025 -1100);
PAINT WHITE (6025 -1100);
DISPLAY INVISIBLE (6025 -1100);
FORCEPROP 1 LAST PART_NUMBER CS24702FB06
J 0
(6015 -1400);
DISPLAY 0.787234 (6015 -1400);
DISPLAY INVISIBLE (6015 -1400);
FORCEADD UNIVERSAL_POWER..1
(5975 -1075);
FORCEPROP 3 LASTPIN (5975 -1125) SIG_NAME P3V3_AUX\g
J 0
(5985 -1115);
DISPLAY 0.659574 (5985 -1115);
PAINT MONO (5985 -1115);
DISPLAY INVISIBLE (5985 -1115);
FORCEPROP 1 LAST HDL_POWER P3V3_AUX
J 1
(5975 -1025);
DISPLAY 0.872340 (5975 -1025);
PAINT GREEN (5975 -1025);
FORCEPROP 2 LAST CDS_LIB pure_quanta_power
J 0
(5975 -1075);
DISPLAY INVISIBLE (5975 -1075);
FORCEPROP 1 LAST PATH I19
J 0
(6025 -1050);
DISPLAY 0.872340 (6025 -1050);
PAINT AQUA (6025 -1050);
DISPLAY INVISIBLE (6025 -1050);
FORCEADD OFFPAGE..1
(2825 -1675);
FORCEPROP 2 LAST $XR0 137 
J 0
(2573 -1675);
DISPLAY 0.638298 (2573 -1675);
PAINT MONO (2573 -1675);
FORCEPROP 2 LAST CDS_LIB standard
J 0
(2825 -1675);
PAINT MONO (2825 -1675);
DISPLAY INVISIBLE (2825 -1675);
FORCEPROP 1 LAST OFFPAGE TRUE
J 0
(3150 -1800);
DISPLAY 0.872340 (3150 -1800);
PAINT GREEN (3150 -1800);
DISPLAY INVISIBLE (3150 -1800);
FORCEPROP 1 LAST COMMENT_BODY TRUE
J 0
(2950 -1775);
DISPLAY 0.872340 (2950 -1775);
PAINT GREEN (2950 -1775);
DISPLAY INVISIBLE (2950 -1775);
FORCEPROP 2 LAST PATH I2
J 0
(2550 -1625);
DISPLAY 0.680851 (2550 -1625);
DISPLAY INVISIBLE (2550 -1625);
FORCEADD UNIVERSAL_POWER..1
(5150 -900);
FORCEPROP 3 LASTPIN (5150 -950) SIG_NAME P3V3_AUX\g
J 0
(5160 -940);
DISPLAY 0.659574 (5160 -940);
PAINT MONO (5160 -940);
DISPLAY INVISIBLE (5160 -940);
FORCEPROP 1 LAST HDL_POWER P3V3_AUX
J 1
(5150 -850);
DISPLAY 0.872340 (5150 -850);
PAINT GREEN (5150 -850);
FORCEPROP 2 LAST CDS_LIB pure_quanta_power
J 0
(5150 -900);
PAINT MONO (5150 -900);
DISPLAY INVISIBLE (5150 -900);
FORCEPROP 1 LAST PATH I20
J 0
(5200 -875);
DISPLAY 0.872340 (5200 -875);
PAINT AQUA (5200 -875);
DISPLAY INVISIBLE (5200 -875);
FORCEADD UNIVERSAL_GND..1
(5300 -725);
FORCEPROP 3 LASTPIN (5300 -675) SIG_NAME GND\g
J 0
(5310 -665);
DISPLAY 0.659574 (5310 -665);
PAINT MONO (5310 -665);
DISPLAY INVISIBLE (5310 -665);
FORCEPROP 2 LAST CDS_LIB pure_quanta_power
J 0
(5300 -725);
PAINT MONO (5300 -725);
DISPLAY INVISIBLE (5300 -725);
FORCEPROP 1 LAST HDL_POWER GND
J 1
(5325 -800);
DISPLAY 0.872340 (5325 -800);
PAINT GREEN (5325 -800);
DISPLAY INVISIBLE (5325 -800);
FORCEPROP 1 LAST PATH I21
J 0
(5375 -725);
DISPLAY 0.872340 (5375 -725);
PAINT AQUA (5375 -725);
DISPLAY INVISIBLE (5375 -725);
FORCEADD 74LVC1G07GV..1
(5775 -400);
FORCEPROP 1 LAST LOCATION U218
J 0
(5650 -75);
DISPLAY 0.723404 (5650 -75);
PAINT GREEN (5650 -75);
FORCEPROP 0 LAST $SEC 1
J 0
(5650 125);
DISPLAY 0.680851 (5650 125);
PAINT MONO (5650 125);
DISPLAY INVISIBLE (5650 125);
FORCEPROP 0 LAST CDS_SEC 1
J 0
(5650 125);
DISPLAY 1.021277 (5650 125);
DISPLAY INVISIBLE (5650 125);
FORCEPROP 0 LASTPIN (5500 -400) $PN 2
J 2
(5490 -390);
DISPLAY 0.680851 (5490 -390);
PAINT MONO (5490 -390);
FORCEPROP 0 LASTPIN (5500 -500) $PN 3
J 2
(5490 -490);
DISPLAY 0.680851 (5490 -490);
PAINT MONO (5490 -490);
FORCEPROP 0 LASTPIN (5500 -300) $PN 1
J 2
(5490 -290);
DISPLAY 0.680851 (5490 -290);
PAINT MONO (5490 -290);
FORCEPROP 0 LASTPIN (6050 -300) $PN 5
J 0
(6060 -290);
DISPLAY 0.680851 (6060 -290);
PAINT MONO (6060 -290);
FORCEPROP 0 LASTPIN (6050 -500) $PN 4
J 0
(6060 -490);
DISPLAY 0.680851 (6060 -490);
PAINT MONO (6060 -490);
FORCEPROP 2 LAST VALUE 74LVC1G07GV
J 0
(5650 25);
DISPLAY 0.638298 (5650 25);
FORCEPROP 2 LAST PART_TYPE SMLF
J 0
(5650 75);
DISPLAY 0.638298 (5650 75);
FORCEPROP 1 LAST MATERIAL IC
J 0
(5656 -218);
DISPLAY 0.723404 (5656 -218);
PAINT GREEN (5656 -218);
FORCEPROP 2 LAST CDS_LIB pure_quanta
J 0
(5775 -400);
DISPLAY INVISIBLE (5775 -400);
FORCEPROP 1 LAST NEEDS_NO_SIZE TRUE
J 0
(5775 -400);
DISPLAY 0.723404 (5775 -400);
PAINT GREEN (5775 -400);
DISPLAY INVISIBLE (5775 -400);
FORCEPROP 1 LAST CDS_LMAN_SYM_OUTLINE -125,150,125,-150
J 0
(5775 -400);
DISPLAY 0.468085 (5775 -400);
PAINT GREEN (5775 -400);
DISPLAY INVISIBLE (5775 -400);
FORCEPROP 1 LAST PATH I22
J 0
(5775 -400);
DISPLAY 0.723404 (5775 -400);
PAINT GREEN (5775 -400);
DISPLAY INVISIBLE (5775 -400);
FORCEPROP 1 LAST PART_NUMBER AL1G0007001
J 0
(5650 -150);
DISPLAY 0.723404 (5650 -150);
PAINT GREEN (5650 -150);
DISPLAY INVISIBLE (5650 -150);
FORCEADD UNIVERSAL_GND..1
(6825 -3550);
FORCEPROP 3 LASTPIN (6825 -3500) SIG_NAME GND\g
J 0
(6835 -3490);
DISPLAY 0.659574 (6835 -3490);
PAINT MONO (6835 -3490);
DISPLAY INVISIBLE (6835 -3490);
FORCEPROP 2 LAST CDS_LIB pure_quanta_power
J 0
(6825 -3550);
PAINT MONO (6825 -3550);
DISPLAY INVISIBLE (6825 -3550);
FORCEPROP 1 LAST HDL_POWER GND
J 1
(6850 -3625);
DISPLAY 0.872340 (6850 -3625);
PAINT GREEN (6850 -3625);
DISPLAY INVISIBLE (6850 -3625);
FORCEPROP 1 LAST PATH I23
J 0
(6900 -3550);
DISPLAY 0.872340 (6900 -3550);
PAINT AQUA (6900 -3550);
DISPLAY INVISIBLE (6900 -3550);
FORCEADD Q_RES..2
(6825 -3325);
FORCEPROP 1 LAST LOCATION R3235
J 0
(6870 -3200);
DISPLAY 0.787234 (6870 -3200);
FORCEPROP 2 LAST $SEC 1
J 0
(6875 -3100);
DISPLAY 0.680851 (6875 -3100);
PAINT MONO (6875 -3100);
DISPLAY INVISIBLE (6875 -3100);
FORCEPROP 2 LAST CDS_SEC 1
J 0
(6875 -3100);
DISPLAY 1.021277 (6875 -3100);
DISPLAY INVISIBLE (6875 -3100);
FORCEPROP 1 LASTPIN (6825 -3225) $PN 1
J 0
(6830 -3263);
DISPLAY 0.787234 (6830 -3263);
FORCEPROP 1 LASTPIN (6825 -3425) $PN 2
J 0
(6830 -3415);
DISPLAY 0.787234 (6830 -3415);
FORCEPROP 1 LAST TOLERANCE 1%
J 0
(6870 -3300);
DISPLAY 0.638298 (6870 -3300);
FORCEPROP 1 LAST WATTAGE 1/16W
J 0
(6865 -3350);
DISPLAY 0.638298 (6865 -3350);
FORCEPROP 1 LAST MATERIAL CHIP
J 0
(6865 -3400);
DISPLAY 0.638298 (6865 -3400);
FORCEPROP 1 LAST PACK_TYPE 0402LF
J 0
(6865 -3500);
DISPLAY 0.638298 (6865 -3500);
FORCEPROP 1 LAST VALUE 100K
J 0
(6870 -3250);
DISPLAY 0.638298 (6870 -3250);
FORCEPROP 2 LAST CDS_LIB pure_quanta
J 0
(6825 -3325);
PAINT MONO (6825 -3325);
DISPLAY INVISIBLE (6825 -3325);
FORCEPROP 1 LAST PATH I24
J 0
(6875 -3150);
DISPLAY 0.978723 (6875 -3150);
PAINT WHITE (6875 -3150);
DISPLAY INVISIBLE (6875 -3150);
FORCEPROP 1 LAST PART_NUMBER CS41002FB09
J 0
(6865 -3450);
DISPLAY 0.638298 (6865 -3450);
DISPLAY INVISIBLE (6865 -3450);
FORCEADD Q_RES..1
(7100 -3125);
FORCEPROP 1 LAST LOCATION R3236
J 0
(6875 -3125);
DISPLAY 0.787234 (6875 -3125);
FORCEPROP 0 LAST $SEC 1
J 0
(7350 -3000);
DISPLAY 0.680851 (7350 -3000);
PAINT MONO (7350 -3000);
DISPLAY INVISIBLE (7350 -3000);
FORCEPROP 0 LAST CDS_SEC 1
J 0
(7350 -3000);
DISPLAY 1.021277 (7350 -3000);
DISPLAY INVISIBLE (7350 -3000);
FORCEPROP 1 LASTPIN (7000 -3125) $PN 1
J 0
(7012 -3113);
DISPLAY 0.787234 (7012 -3113);
PAINT MONO (7012 -3113);
FORCEPROP 1 LASTPIN (7200 -3125) $PN 2
J 0
(7162 -3113);
DISPLAY 0.787234 (7162 -3113);
PAINT MONO (7162 -3113);
FORCEPROP 1 LAST VALUE 0
J 2
(7225 -3125);
DISPLAY 0.510638 (7225 -3125);
FORCEPROP 1 LAST PACK_TYPE 0402LF
J 0
(7000 -3025);
DISPLAY 0.510638 (7000 -3025);
FORCEPROP 1 LAST MATERIAL CHIP
J 0
(7325 -3125);
DISPLAY 0.510638 (7325 -3125);
FORCEPROP 1 LAST TOLERANCE 5%
J 0
(7250 -3125);
DISPLAY 0.510638 (7250 -3125);
FORCEPROP 1 LAST WATTAGE 1/16W
J 2
(7350 -3025);
DISPLAY 0.510638 (7350 -3025);
FORCEPROP 2 LAST CDS_LIB pure_quanta
J 0
(7100 -3125);
DISPLAY INVISIBLE (7100 -3125);
FORCEPROP 1 LAST PATH I25
J 0
(7050 -2975);
DISPLAY 0.978723 (7050 -2975);
PAINT WHITE (7050 -2975);
DISPLAY INVISIBLE (7050 -2975);
FORCEPROP 1 LAST PART_NUMBER CS00002JB13
J 0
(7000 -3075);
DISPLAY 0.510638 (7000 -3075);
DISPLAY INVISIBLE (7000 -3075);
FORCEADD OFFPAGE..2
R 2
(7525 -3425);
FORCEPROP 2 LAST $XR0 137 
J 0
(7270 -3425);
DISPLAY 0.638298 (7270 -3425);
PAINT MONO (7270 -3425);
FORCEPROP 2 LAST CDS_LIB standard
J 2
(7525 -3425);
DISPLAY INVISIBLE (7525 -3425);
FORCEPROP 1 LAST OFFPAGE TRUE
J 2
(7200 -3550);
DISPLAY 0.872340 (7200 -3550);
PAINT GREEN (7200 -3550);
DISPLAY INVISIBLE (7200 -3550);
FORCEPROP 1 LAST COMMENT_BODY TRUE
J 2
(7570 -3520);
DISPLAY 0.872340 (7570 -3520);
PAINT GREEN (7570 -3520);
DISPLAY INVISIBLE (7570 -3520);
FORCEPROP 2 LAST PATH I26
J 0
(7250 -3375);
DISPLAY 0.680851 (7250 -3375);
DISPLAY INVISIBLE (7250 -3375);
FORCEADD OFFPAGE..2
(8075 -3125);
FORCEPROP 2 LAST $XR0 137 
J 0
(8264 -3125);
DISPLAY 0.638298 (8264 -3125);
PAINT MONO (8264 -3125);
FORCEPROP 2 LAST CDS_LIB standard
J 0
(8075 -3125);
DISPLAY INVISIBLE (8075 -3125);
FORCEPROP 1 LAST OFFPAGE TRUE
J 0
(8400 -3250);
DISPLAY 0.872340 (8400 -3250);
PAINT GREEN (8400 -3250);
DISPLAY INVISIBLE (8400 -3250);
FORCEPROP 1 LAST COMMENT_BODY TRUE
J 0
(8030 -3220);
DISPLAY 0.872340 (8030 -3220);
PAINT GREEN (8030 -3220);
DISPLAY INVISIBLE (8030 -3220);
FORCEPROP 2 LAST PATH I27
J 0
(8275 -3075);
DISPLAY 0.680851 (8275 -3075);
DISPLAY INVISIBLE (8275 -3075);
FORCEADD UNIVERSAL_GND..1
(7600 -2050);
FORCEPROP 3 LASTPIN (7600 -2000) SIG_NAME GND\g
J 0
(7610 -1990);
DISPLAY 0.659574 (7610 -1990);
PAINT MONO (7610 -1990);
DISPLAY INVISIBLE (7610 -1990);
FORCEPROP 2 LAST CDS_LIB pure_quanta_power
J 0
(7600 -2050);
DISPLAY INVISIBLE (7600 -2050);
FORCEPROP 1 LAST HDL_POWER GND
J 1
(7625 -2125);
DISPLAY 0.872340 (7625 -2125);
PAINT GREEN (7625 -2125);
DISPLAY INVISIBLE (7625 -2125);
FORCEPROP 1 LAST PATH I28
J 0
(7675 -2050);
DISPLAY 0.872340 (7675 -2050);
PAINT AQUA (7675 -2050);
DISPLAY INVISIBLE (7675 -2050);
FORCEADD Q_RES..1
(6300 -1725);
FORCEPROP 1 LAST LOCATION R3185
J 0
(6050 -1725);
DISPLAY 0.638298 (6050 -1725);
FORCEPROP 2 LAST $SEC 1
J 0
(6250 -1525);
DISPLAY 0.680851 (6250 -1525);
PAINT MONO (6250 -1525);
DISPLAY INVISIBLE (6250 -1525);
FORCEPROP 2 LAST CDS_SEC 1
J 0
(6250 -1525);
DISPLAY 1.021277 (6250 -1525);
DISPLAY INVISIBLE (6250 -1525);
FORCEPROP 1 LASTPIN (6200 -1725) $PN 1
J 0
(6212 -1713);
DISPLAY 0.787234 (6212 -1713);
FORCEPROP 1 LASTPIN (6400 -1725) $PN 2
J 0
(6362 -1713);
DISPLAY 0.787234 (6362 -1713);
FORCEPROP 1 LAST MATERIAL CHIP
J 0
(6625 -1725);
DISPLAY 0.510638 (6625 -1725);
FORCEPROP 1 LAST VALUE 33.2
J 2
(6500 -1725);
DISPLAY 0.510638 (6500 -1725);
FORCEPROP 1 LAST TOLERANCE 1%
J 0
(6525 -1725);
DISPLAY 0.510638 (6525 -1725);
FORCEPROP 1 LAST WATTAGE 1/16W
J 2
(6475 -1600);
DISPLAY 0.510638 (6475 -1600);
FORCEPROP 1 LAST PACK_TYPE 0402LF
J 0
(6175 -1600);
DISPLAY 0.510638 (6175 -1600);
FORCEPROP 2 LAST CDS_LIB pure_quanta
J 0
(6300 -1725);
PAINT MONO (6300 -1725);
DISPLAY INVISIBLE (6300 -1725);
FORCEPROP 1 LAST PATH I29
J 0
(6250 -1575);
DISPLAY 0.978723 (6250 -1575);
PAINT WHITE (6250 -1575);
DISPLAY INVISIBLE (6250 -1575);
FORCEPROP 1 LAST PART_NUMBER CS03322FB03
J 0
(6200 -1650);
DISPLAY 0.510638 (6200 -1650);
DISPLAY INVISIBLE (6200 -1650);
FORCEADD Q_RES..2
R 2
(3350 -1375);
FORCEPROP 1 LAST LOCATION R3182
J 2
(3305 -1250);
DISPLAY 0.787234 (3305 -1250);
FORCEPROP 2 LAST $SEC 1
J 0
(3300 -1150);
DISPLAY 0.680851 (3300 -1150);
PAINT MONO (3300 -1150);
DISPLAY INVISIBLE (3300 -1150);
FORCEPROP 2 LAST CDS_SEC 1
J 0
(3300 -1150);
DISPLAY 1.021277 (3300 -1150);
DISPLAY INVISIBLE (3300 -1150);
FORCEPROP 1 LASTPIN (3350 -1275) $PN 1
J 2
(3345 -1313);
DISPLAY 0.787234 (3345 -1313);
FORCEPROP 1 LASTPIN (3350 -1475) $PN 2
J 2
(3345 -1465);
DISPLAY 0.787234 (3345 -1465);
FORCEPROP 1 LAST MATERIAL CHIP
J 2
(3310 -1450);
DISPLAY 0.638298 (3310 -1450);
FORCEPROP 1 LAST PACK_TYPE 0402LF
J 2
(3310 -1550);
DISPLAY 0.638298 (3310 -1550);
FORCEPROP 1 LAST WATTAGE 1/16W
J 2
(3310 -1400);
DISPLAY 0.638298 (3310 -1400);
FORCEPROP 1 LAST TOLERANCE 1%
J 2
(3305 -1350);
DISPLAY 0.638298 (3305 -1350);
FORCEPROP 1 LAST VALUE 10K
J 2
(3305 -1300);
DISPLAY 0.638298 (3305 -1300);
FORCEPROP 2 LAST CDS_LIB pure_quanta
J 2
(3350 -1375);
PAINT MONO (3350 -1375);
DISPLAY INVISIBLE (3350 -1375);
FORCEPROP 1 LAST PATH I3
J 2
(3300 -1200);
DISPLAY 0.978723 (3300 -1200);
PAINT WHITE (3300 -1200);
DISPLAY INVISIBLE (3300 -1200);
FORCEPROP 1 LAST PART_NUMBER CS31002FB08
J 2
(3310 -1500);
DISPLAY 0.638298 (3310 -1500);
DISPLAY INVISIBLE (3310 -1500);
FORCEADD UNIVERSAL_GND..1
(6450 -250);
FORCEPROP 3 LASTPIN (6450 -200) SIG_NAME GND\g
J 0
(6460 -190);
DISPLAY 0.659574 (6460 -190);
PAINT MONO (6460 -190);
DISPLAY INVISIBLE (6460 -190);
FORCEPROP 2 LAST CDS_LIB pure_quanta_power
J 0
(6450 -250);
PAINT MONO (6450 -250);
DISPLAY INVISIBLE (6450 -250);
FORCEPROP 1 LAST HDL_POWER GND
J 1
(6475 -325);
DISPLAY 0.872340 (6475 -325);
PAINT GREEN (6475 -325);
DISPLAY INVISIBLE (6475 -325);
FORCEPROP 1 LAST PATH I30
J 0
(6525 -250);
DISPLAY 0.872340 (6525 -250);
PAINT AQUA (6525 -250);
DISPLAY INVISIBLE (6525 -250);
FORCEADD Q_CAP..1
(6450 -25);
FORCEPROP 1 LAST LOCATION C1823
J 0
(6500 75);
DISPLAY 0.978723 (6500 75);
FORCEPROP 2 LAST $SEC 1
J 0
(6500 175);
DISPLAY 0.680851 (6500 175);
PAINT MONO (6500 175);
DISPLAY INVISIBLE (6500 175);
FORCEPROP 2 LAST CDS_SEC 1
J 0
(6500 175);
DISPLAY 1.021277 (6500 175);
DISPLAY INVISIBLE (6500 175);
FORCEPROP 1 LASTPIN (6450 75) $PN 1
J 0
(6460 55);
DISPLAY 0.787234 (6460 55);
FORCEPROP 1 LASTPIN (6450 -125) $PN 2
J 0
(6460 -145);
DISPLAY 0.787234 (6460 -145);
FORCEPROP 1 LAST PACK_TYPE 0402
J 0
(6500 -225);
DISPLAY 0.510638 (6500 -225);
FORCEPROP 1 LAST TOLERANCE 10%
J 0
(6500 -75);
DISPLAY 0.510638 (6500 -75);
FORCEPROP 1 LAST MATERIAL X7R
J 0
(6500 -125);
DISPLAY 0.510638 (6500 -125);
FORCEPROP 1 LAST VALUE 0.1UF
J 0
(6500 25);
DISPLAY 0.510638 (6500 25);
FORCEPROP 1 LAST VOLTAGE 25V
J 0
(6500 -25);
DISPLAY 0.510638 (6500 -25);
FORCEPROP 2 LAST CDS_LIB pure_quanta
J 2
(6450 -25);
PAINT MONO (6450 -25);
DISPLAY INVISIBLE (6450 -25);
FORCEPROP 1 LAST PATH I31
J 0
(6500 125);
DISPLAY 0.978723 (6500 125);
PAINT WHITE (6500 125);
DISPLAY INVISIBLE (6500 125);
FORCEPROP 1 LAST PART_NUMBER CH4104K1B00
J 0
(6500 -175);
DISPLAY 0.510638 (6500 -175);
DISPLAY INVISIBLE (6500 -175);
FORCEADD 74LVC1G07GV..1
(8075 -1725);
FORCEPROP 1 LAST LOCATION U219
J 0
(7950 -1400);
DISPLAY 0.723404 (7950 -1400);
PAINT GREEN (7950 -1400);
FORCEPROP 0 LAST $SEC 1
J 0
(7950 -1200);
DISPLAY 0.680851 (7950 -1200);
PAINT MONO (7950 -1200);
DISPLAY INVISIBLE (7950 -1200);
FORCEPROP 0 LAST CDS_SEC 1
J 0
(7950 -1200);
DISPLAY 1.021277 (7950 -1200);
DISPLAY INVISIBLE (7950 -1200);
FORCEPROP 0 LASTPIN (7800 -1725) $PN 2
J 2
(7790 -1715);
DISPLAY 0.680851 (7790 -1715);
PAINT MONO (7790 -1715);
FORCEPROP 0 LASTPIN (7800 -1825) $PN 3
J 2
(7790 -1815);
DISPLAY 0.680851 (7790 -1815);
PAINT MONO (7790 -1815);
FORCEPROP 0 LASTPIN (7800 -1625) $PN 1
J 2
(7790 -1615);
DISPLAY 0.680851 (7790 -1615);
PAINT MONO (7790 -1615);
FORCEPROP 0 LASTPIN (8350 -1625) $PN 5
J 0
(8360 -1615);
DISPLAY 0.680851 (8360 -1615);
PAINT MONO (8360 -1615);
FORCEPROP 0 LASTPIN (8350 -1825) $PN 4
J 0
(8360 -1815);
DISPLAY 0.680851 (8360 -1815);
PAINT MONO (8360 -1815);
FORCEPROP 2 LAST PART_TYPE SMLF
J 0
(7950 -1250);
DISPLAY 0.638298 (7950 -1250);
FORCEPROP 2 LAST VALUE 74LVC1G07GV
J 0
(7950 -1300);
DISPLAY 0.638298 (7950 -1300);
FORCEPROP 1 LAST MATERIAL IC
J 0
(7956 -1543);
DISPLAY 0.723404 (7956 -1543);
PAINT GREEN (7956 -1543);
FORCEPROP 2 LAST CDS_LIB pure_quanta
J 0
(8075 -1725);
DISPLAY INVISIBLE (8075 -1725);
FORCEPROP 1 LAST CDS_LMAN_SYM_OUTLINE -125,150,125,-150
J 0
(8075 -1725);
DISPLAY 0.468085 (8075 -1725);
PAINT GREEN (8075 -1725);
DISPLAY INVISIBLE (8075 -1725);
FORCEPROP 1 LAST NEEDS_NO_SIZE TRUE
J 0
(8075 -1725);
DISPLAY 0.723404 (8075 -1725);
PAINT GREEN (8075 -1725);
DISPLAY INVISIBLE (8075 -1725);
FORCEPROP 1 LAST PATH I32
J 0
(8075 -1725);
DISPLAY 0.723404 (8075 -1725);
PAINT GREEN (8075 -1725);
DISPLAY INVISIBLE (8075 -1725);
FORCEPROP 1 LAST PART_NUMBER AL1G0007001
J 0
(7950 -1475);
DISPLAY 0.723404 (7950 -1475);
PAINT GREEN (7950 -1475);
DISPLAY INVISIBLE (7950 -1475);
FORCEADD Q_RES..1
(7700 -500);
FORCEPROP 1 LAST LOCATION R3191
J 0
(7425 -500);
DISPLAY 0.638298 (7425 -500);
FORCEPROP 2 LAST $SEC 1
J 0
(7650 -300);
DISPLAY 0.680851 (7650 -300);
PAINT MONO (7650 -300);
DISPLAY INVISIBLE (7650 -300);
FORCEPROP 2 LAST CDS_SEC 1
J 0
(7650 -300);
DISPLAY 1.021277 (7650 -300);
DISPLAY INVISIBLE (7650 -300);
FORCEPROP 1 LASTPIN (7600 -500) $PN 1
J 0
(7612 -488);
DISPLAY 0.787234 (7612 -488);
FORCEPROP 1 LASTPIN (7800 -500) $PN 2
J 0
(7762 -488);
DISPLAY 0.787234 (7762 -488);
FORCEPROP 1 LAST PACK_TYPE 0402LF
J 0
(8000 -500);
DISPLAY 0.510638 (8000 -500);
FORCEPROP 1 LAST MATERIAL CHIP
J 0
(7600 -375);
DISPLAY 0.510638 (7600 -375);
FORCEPROP 1 LAST VALUE 33.2
J 2
(7900 -500);
DISPLAY 0.510638 (7900 -500);
FORCEPROP 1 LAST WATTAGE 1/16W
J 2
(7875 -375);
DISPLAY 0.510638 (7875 -375);
FORCEPROP 1 LAST TOLERANCE 1%
J 0
(7925 -500);
DISPLAY 0.510638 (7925 -500);
FORCEPROP 2 LAST CDS_LIB pure_quanta
J 0
(7700 -500);
PAINT MONO (7700 -500);
DISPLAY INVISIBLE (7700 -500);
FORCEPROP 1 LAST PATH I33
J 0
(7650 -350);
DISPLAY 0.978723 (7650 -350);
PAINT WHITE (7650 -350);
DISPLAY INVISIBLE (7650 -350);
FORCEPROP 1 LAST PART_NUMBER CS03322FB03
J 0
(7600 -425);
DISPLAY 0.510638 (7600 -425);
DISPLAY INVISIBLE (7600 -425);
FORCEADD Q_RES..2
(7150 -125);
FORCEPROP 1 LAST LOCATION R3190
J 0
(7195 0);
DISPLAY 0.787234 (7195 0);
FORCEPROP 2 LAST $SEC 1
J 0
(7200 100);
DISPLAY 0.680851 (7200 100);
PAINT MONO (7200 100);
DISPLAY INVISIBLE (7200 100);
FORCEPROP 2 LAST CDS_SEC 1
J 0
(7200 100);
DISPLAY 1.021277 (7200 100);
DISPLAY INVISIBLE (7200 100);
FORCEPROP 1 LASTPIN (7150 -25) $PN 1
J 0
(7155 -63);
DISPLAY 0.787234 (7155 -63);
FORCEPROP 1 LASTPIN (7150 -225) $PN 2
J 0
(7155 -215);
DISPLAY 0.787234 (7155 -215);
FORCEPROP 1 LAST VALUE 4.7K
J 0
(7195 -50);
DISPLAY 0.787234 (7195 -50);
FORCEPROP 1 LAST TOLERANCE 1%
J 0
(7195 -100);
DISPLAY 0.787234 (7195 -100);
FORCEPROP 1 LAST MATERIAL CHIP
J 0
(7190 -200);
DISPLAY 0.787234 (7190 -200);
PAINT RED (7190 -200);
FORCEPROP 1 LAST PACK_TYPE 0402LF
J 0
(7190 -300);
DISPLAY 0.787234 (7190 -300);
FORCEPROP 1 LAST WATTAGE 1/16W
J 0
(7190 -150);
DISPLAY 0.787234 (7190 -150);
FORCEPROP 2 LAST CDS_LIB pure_quanta
J 0
(7150 -125);
PAINT MONO (7150 -125);
DISPLAY INVISIBLE (7150 -125);
FORCEPROP 1 LAST PATH I34
J 0
(7200 50);
DISPLAY 0.978723 (7200 50);
PAINT WHITE (7200 50);
DISPLAY INVISIBLE (7200 50);
FORCEPROP 1 LAST PART_NUMBER CS24702FB06
J 0
(7190 -250);
DISPLAY 0.787234 (7190 -250);
DISPLAY INVISIBLE (7190 -250);
FORCEADD UNIVERSAL_POWER..1
(7150 75);
FORCEPROP 3 LASTPIN (7150 25) SIG_NAME P3V3_AUX\g
J 0
(7160 35);
DISPLAY 0.659574 (7160 35);
PAINT MONO (7160 35);
DISPLAY INVISIBLE (7160 35);
FORCEPROP 1 LAST HDL_POWER P3V3_AUX
J 1
(7150 125);
DISPLAY 0.872340 (7150 125);
PAINT GREEN (7150 125);
FORCEPROP 2 LAST CDS_LIB pure_quanta_power
J 0
(7150 75);
PAINT MONO (7150 75);
DISPLAY INVISIBLE (7150 75);
FORCEPROP 1 LAST PATH I35
J 0
(7200 100);
DISPLAY 0.872340 (7200 100);
PAINT AQUA (7200 100);
DISPLAY INVISIBLE (7200 100);
FORCEADD Q_RES..1
(8575 -3425);
FORCEPROP 1 LAST LOCATION R4602
J 0
(8350 -3425);
DISPLAY 0.787234 (8350 -3425);
FORCEPROP 0 LAST $SEC 1
J 0
(8400 -3375);
DISPLAY 0.680851 (8400 -3375);
PAINT MONO (8400 -3375);
DISPLAY INVISIBLE (8400 -3375);
FORCEPROP 0 LAST CDS_SEC 1
J 0
(8400 -3375);
DISPLAY 1.021277 (8400 -3375);
DISPLAY INVISIBLE (8400 -3375);
FORCEPROP 1 LASTPIN (8475 -3425) $PN 1
J 0
(8487 -3413);
DISPLAY 0.787234 (8487 -3413);
PAINT MONO (8487 -3413);
FORCEPROP 1 LASTPIN (8675 -3425) $PN 2
J 0
(8637 -3413);
DISPLAY 0.787234 (8637 -3413);
PAINT MONO (8637 -3413);
FORCEPROP 1 LAST MATERIAL CHIP
J 0
(8800 -3425);
DISPLAY 0.510638 (8800 -3425);
FORCEPROP 1 LAST VALUE 0
J 2
(8700 -3425);
DISPLAY 0.510638 (8700 -3425);
FORCEPROP 2 LAST CDS_LIB pure_quanta
J 0
(8575 -3425);
DISPLAY INVISIBLE (8575 -3425);
FORCEPROP 1 LAST PACK_TYPE 0402LF
J 0
(8475 -3325);
DISPLAY 0.510638 (8475 -3325);
DISPLAY INVISIBLE (8475 -3325);
FORCEPROP 1 LAST TOLERANCE 5%
J 0
(8725 -3425);
DISPLAY 0.510638 (8725 -3425);
DISPLAY INVISIBLE (8725 -3425);
FORCEPROP 1 LAST WATTAGE 1/16W
J 2
(8825 -3325);
DISPLAY 0.510638 (8825 -3325);
DISPLAY INVISIBLE (8825 -3325);
FORCEPROP 1 LAST PATH I36
J 0
(8525 -3275);
DISPLAY 0.978723 (8525 -3275);
PAINT WHITE (8525 -3275);
DISPLAY INVISIBLE (8525 -3275);
FORCEPROP 1 LAST PART_NUMBER CS00002JB13
J 0
(8475 -3375);
DISPLAY 0.510638 (8475 -3375);
DISPLAY INVISIBLE (8475 -3375);
FORCEADD OFFPAGE..1
(8725 -3325);
FORCEPROP 2 LAST $XR0 133 
J 0
(8443 -3325);
DISPLAY 0.638298 (8443 -3325);
PAINT MONO (8443 -3325);
FORCEPROP 2 LAST CDS_LIB standard
J 0
(8725 -3325);
DISPLAY INVISIBLE (8725 -3325);
FORCEPROP 1 LAST OFFPAGE TRUE
J 0
(9050 -3450);
DISPLAY 0.872340 (9050 -3450);
PAINT GREEN (9050 -3450);
DISPLAY INVISIBLE (9050 -3450);
FORCEPROP 1 LAST COMMENT_BODY TRUE
J 0
(8850 -3425);
DISPLAY 0.872340 (8850 -3425);
PAINT GREEN (8850 -3425);
DISPLAY INVISIBLE (8850 -3425);
FORCEPROP 2 LAST PATH I37
J 0
(8475 -3275);
DISPLAY 0.680851 (8475 -3275);
DISPLAY INVISIBLE (8475 -3275);
FORCEADD UNIVERSAL_GND..1
(9700 -3675);
FORCEPROP 3 LASTPIN (9700 -3625) SIG_NAME GND\g
J 0
(9710 -3615);
DISPLAY 0.659574 (9710 -3615);
PAINT MONO (9710 -3615);
DISPLAY INVISIBLE (9710 -3615);
FORCEPROP 2 LAST CDS_LIB pure_quanta_power
J 0
(9700 -3675);
DISPLAY INVISIBLE (9700 -3675);
FORCEPROP 1 LAST HDL_POWER GND
J 1
(9725 -3750);
DISPLAY 0.872340 (9725 -3750);
PAINT GREEN (9725 -3750);
DISPLAY INVISIBLE (9725 -3750);
FORCEPROP 1 LAST PATH I38
J 0
(9775 -3675);
DISPLAY 0.872340 (9775 -3675);
PAINT AQUA (9775 -3675);
DISPLAY INVISIBLE (9775 -3675);
FORCEADD UNIVERSAL_POWER..1
(8500 -1175);
FORCEPROP 3 LASTPIN (8500 -1225) SIG_NAME P3V3_AUX\g
J 0
(8510 -1215);
DISPLAY 0.659574 (8510 -1215);
PAINT MONO (8510 -1215);
DISPLAY INVISIBLE (8510 -1215);
FORCEPROP 1 LAST HDL_POWER P3V3_AUX
J 1
(8500 -1125);
DISPLAY 0.872340 (8500 -1125);
PAINT GREEN (8500 -1125);
FORCEPROP 2 LAST CDS_LIB pure_quanta_power
J 0
(8500 -1175);
DISPLAY INVISIBLE (8500 -1175);
FORCEPROP 1 LAST PATH I39
J 0
(8550 -1150);
DISPLAY 0.872340 (8550 -1150);
PAINT AQUA (8550 -1150);
DISPLAY INVISIBLE (8550 -1150);
FORCEADD Q_RES..2
(3625 -1375);
FORCEPROP 1 LAST LOCATION R3183
J 0
(3670 -1250);
DISPLAY 0.808511 (3670 -1250);
FORCEPROP 2 LAST $SEC 1
J 2
(3675 -1150);
DISPLAY 0.680851 (3675 -1150);
PAINT MONO (3675 -1150);
DISPLAY INVISIBLE (3675 -1150);
FORCEPROP 2 LAST CDS_SEC 1
J 2
(3675 -1150);
DISPLAY 1.021277 (3675 -1150);
DISPLAY INVISIBLE (3675 -1150);
FORCEPROP 1 LASTPIN (3625 -1275) $PN 1
J 0
(3630 -1313);
DISPLAY 0.787234 (3630 -1313);
FORCEPROP 1 LASTPIN (3625 -1475) $PN 2
J 0
(3630 -1465);
DISPLAY 0.787234 (3630 -1465);
FORCEPROP 1 LAST MATERIAL CHIP
J 0
(3665 -1450);
DISPLAY 0.638298 (3665 -1450);
FORCEPROP 1 LAST WATTAGE 1/16W
J 0
(3665 -1400);
DISPLAY 0.638298 (3665 -1400);
FORCEPROP 1 LAST VALUE 10K
J 0
(3670 -1300);
DISPLAY 0.638298 (3670 -1300);
FORCEPROP 1 LAST TOLERANCE 1%
J 0
(3670 -1350);
DISPLAY 0.638298 (3670 -1350);
FORCEPROP 1 LAST PACK_TYPE 0402LF
J 0
(3665 -1550);
DISPLAY 0.638298 (3665 -1550);
FORCEPROP 2 LAST CDS_LIB pure_quanta
J 0
(3625 -1375);
PAINT MONO (3625 -1375);
DISPLAY INVISIBLE (3625 -1375);
FORCEPROP 1 LAST PATH I4
J 0
(3675 -1200);
DISPLAY 0.978723 (3675 -1200);
PAINT WHITE (3675 -1200);
DISPLAY INVISIBLE (3675 -1200);
FORCEPROP 1 LAST PART_NUMBER CS31002FB08
J 0
(3665 -1500);
DISPLAY 0.638298 (3665 -1500);
DISPLAY INVISIBLE (3665 -1500);
FORCEADD UNIVERSAL_GND..1
(8700 -1675);
FORCEPROP 3 LASTPIN (8700 -1625) SIG_NAME GND\g
J 0
(8710 -1615);
DISPLAY 0.659574 (8710 -1615);
PAINT MONO (8710 -1615);
DISPLAY INVISIBLE (8710 -1615);
FORCEPROP 2 LAST CDS_LIB pure_quanta_power
J 0
(8700 -1675);
DISPLAY INVISIBLE (8700 -1675);
FORCEPROP 1 LAST HDL_POWER GND
J 1
(8725 -1750);
DISPLAY 0.872340 (8725 -1750);
PAINT GREEN (8725 -1750);
DISPLAY INVISIBLE (8725 -1750);
FORCEPROP 1 LAST PATH I40
J 0
(8775 -1675);
DISPLAY 0.872340 (8775 -1675);
PAINT AQUA (8775 -1675);
DISPLAY INVISIBLE (8775 -1675);
FORCEADD Q_CAP..1
(8700 -1450);
FORCEPROP 1 LAST LOCATION C1824
J 0
(8750 -1350);
DISPLAY 0.978723 (8750 -1350);
FORCEPROP 0 LAST $SEC 1
J 0
(8750 -1300);
DISPLAY 0.680851 (8750 -1300);
PAINT MONO (8750 -1300);
DISPLAY INVISIBLE (8750 -1300);
FORCEPROP 0 LAST CDS_SEC 1
J 0
(8750 -1300);
DISPLAY 1.021277 (8750 -1300);
DISPLAY INVISIBLE (8750 -1300);
FORCEPROP 1 LASTPIN (8700 -1350) $PN 1
J 0
(8710 -1370);
DISPLAY 0.787234 (8710 -1370);
PAINT MONO (8710 -1370);
FORCEPROP 1 LASTPIN (8700 -1550) $PN 2
J 0
(8710 -1570);
DISPLAY 0.787234 (8710 -1570);
PAINT MONO (8710 -1570);
FORCEPROP 1 LAST VOLTAGE 25V
J 0
(8750 -1450);
DISPLAY 0.510638 (8750 -1450);
FORCEPROP 1 LAST TOLERANCE 10%
J 0
(8750 -1500);
DISPLAY 0.510638 (8750 -1500);
FORCEPROP 1 LAST VALUE 0.1UF
J 0
(8750 -1400);
DISPLAY 0.510638 (8750 -1400);
FORCEPROP 1 LAST MATERIAL X7R
J 0
(8750 -1550);
DISPLAY 0.510638 (8750 -1550);
FORCEPROP 1 LAST PACK_TYPE 0402
J 0
(8750 -1650);
DISPLAY 0.510638 (8750 -1650);
FORCEPROP 2 LAST CDS_LIB pure_quanta
J 0
(8700 -1450);
DISPLAY INVISIBLE (8700 -1450);
FORCEPROP 1 LAST PATH I41
J 0
(8750 -1300);
DISPLAY 0.978723 (8750 -1300);
PAINT WHITE (8750 -1300);
DISPLAY INVISIBLE (8750 -1300);
FORCEPROP 1 LAST PART_NUMBER CH4104K1B00
J 0
(8750 -1600);
DISPLAY 0.510638 (8750 -1600);
DISPLAY INVISIBLE (8750 -1600);
FORCEADD OFFPAGE..2
(8950 -500);
FORCEPROP 2 LAST $XR0 137 
J 0
(9139 -500);
DISPLAY 0.638298 (9139 -500);
PAINT MONO (9139 -500);
FORCEPROP 2 LAST CDS_LIB standard
J 0
(8950 -500);
PAINT MONO (8950 -500);
DISPLAY INVISIBLE (8950 -500);
FORCEPROP 1 LAST OFFPAGE TRUE
J 0
(9275 -625);
DISPLAY 0.872340 (9275 -625);
PAINT GREEN (9275 -625);
DISPLAY INVISIBLE (9275 -625);
FORCEPROP 1 LAST COMMENT_BODY TRUE
J 0
(8905 -595);
DISPLAY 0.872340 (8905 -595);
PAINT GREEN (8905 -595);
DISPLAY INVISIBLE (8905 -595);
FORCEPROP 2 LAST PATH I42
J 0
(9150 -450);
DISPLAY 0.680851 (9150 -450);
DISPLAY INVISIBLE (9150 -450);
FORCEADD Q_RES..1
(9550 -1825);
FORCEPROP 1 LAST LOCATION R3193
J 0
(9300 -1825);
DISPLAY 0.638298 (9300 -1825);
FORCEPROP 0 LAST $SEC 1
J 0
(9725 -1675);
DISPLAY 0.680851 (9725 -1675);
PAINT MONO (9725 -1675);
DISPLAY INVISIBLE (9725 -1675);
FORCEPROP 0 LAST CDS_SEC 1
J 0
(9725 -1675);
DISPLAY 1.021277 (9725 -1675);
DISPLAY INVISIBLE (9725 -1675);
FORCEPROP 1 LASTPIN (9450 -1825) $PN 1
J 0
(9462 -1813);
DISPLAY 0.787234 (9462 -1813);
PAINT MONO (9462 -1813);
FORCEPROP 1 LASTPIN (9650 -1825) $PN 2
J 0
(9612 -1813);
DISPLAY 0.787234 (9612 -1813);
PAINT MONO (9612 -1813);
FORCEPROP 1 LAST TOLERANCE 1%
J 0
(9775 -1825);
DISPLAY 0.510638 (9775 -1825);
FORCEPROP 1 LAST VALUE 33.2
J 2
(9750 -1825);
DISPLAY 0.510638 (9750 -1825);
FORCEPROP 1 LAST PACK_TYPE 0402LF
J 0
(9425 -1700);
DISPLAY 0.510638 (9425 -1700);
FORCEPROP 1 LAST MATERIAL CHIP
J 0
(9850 -1825);
DISPLAY 0.510638 (9850 -1825);
FORCEPROP 1 LAST WATTAGE 1/16W
J 2
(9725 -1700);
DISPLAY 0.510638 (9725 -1700);
FORCEPROP 2 LAST CDS_LIB pure_quanta
J 0
(9550 -1825);
DISPLAY INVISIBLE (9550 -1825);
FORCEPROP 1 LAST PATH I43
J 0
(9500 -1675);
DISPLAY 0.978723 (9500 -1675);
PAINT WHITE (9500 -1675);
DISPLAY INVISIBLE (9500 -1675);
FORCEPROP 1 LAST PART_NUMBER CS03322FB03
J 0
(9450 -1750);
DISPLAY 0.510638 (9450 -1750);
DISPLAY INVISIBLE (9450 -1750);
FORCEADD Q_RES..2
(9250 -1375);
FORCEPROP 1 LAST LOCATION R3192
J 0
(9295 -1250);
DISPLAY 0.978723 (9295 -1250);
FORCEPROP 0 LAST $SEC 1
J 0
(9300 -1200);
DISPLAY 0.680851 (9300 -1200);
PAINT MONO (9300 -1200);
DISPLAY INVISIBLE (9300 -1200);
FORCEPROP 0 LAST CDS_SEC 1
J 0
(9300 -1200);
DISPLAY 1.021277 (9300 -1200);
DISPLAY INVISIBLE (9300 -1200);
FORCEPROP 1 LASTPIN (9250 -1275) $PN 1
J 0
(9255 -1313);
DISPLAY 0.787234 (9255 -1313);
PAINT MONO (9255 -1313);
FORCEPROP 1 LASTPIN (9250 -1475) $PN 2
J 0
(9255 -1465);
DISPLAY 0.787234 (9255 -1465);
PAINT MONO (9255 -1465);
FORCEPROP 1 LAST PACK_TYPE 0402LF
J 0
(9290 -1550);
DISPLAY 0.638298 (9290 -1550);
FORCEPROP 1 LAST MATERIAL EMPTY
J 0
(9290 -1450);
DISPLAY 0.638298 (9290 -1450);
PAINT RED (9290 -1450);
FORCEPROP 1 LAST TOLERANCE 1%
J 0
(9295 -1350);
DISPLAY 0.638298 (9295 -1350);
FORCEPROP 1 LAST VALUE 4.7K
J 0
(9295 -1300);
DISPLAY 0.638298 (9295 -1300);
FORCEPROP 1 LAST WATTAGE 1/16W
J 0
(9290 -1400);
DISPLAY 0.638298 (9290 -1400);
FORCEPROP 2 LAST CDS_LIB pure_quanta
J 0
(9250 -1375);
DISPLAY INVISIBLE (9250 -1375);
FORCEPROP 1 LAST PATH I44
J 0
(9300 -1200);
DISPLAY 0.978723 (9300 -1200);
PAINT WHITE (9300 -1200);
DISPLAY INVISIBLE (9300 -1200);
FORCEPROP 1 LAST PART_NUMBER CS24702FB06
J 0
(9290 -1500);
DISPLAY 0.638298 (9290 -1500);
DISPLAY INVISIBLE (9290 -1500);
FORCEADD UNIVERSAL_POWER..1
(9250 -1175);
FORCEPROP 3 LASTPIN (9250 -1225) SIG_NAME P3V3_AUX\g
J 0
(9260 -1215);
DISPLAY 0.659574 (9260 -1215);
PAINT MONO (9260 -1215);
DISPLAY INVISIBLE (9260 -1215);
FORCEPROP 1 LAST HDL_POWER P3V3_AUX
J 1
(9250 -1125);
DISPLAY 0.872340 (9250 -1125);
PAINT GREEN (9250 -1125);
FORCEPROP 2 LAST CDS_LIB pure_quanta_power
J 0
(9250 -1175);
DISPLAY INVISIBLE (9250 -1175);
FORCEPROP 1 LAST PATH I45
J 0
(9300 -1150);
DISPLAY 0.872340 (9300 -1150);
PAINT AQUA (9300 -1150);
DISPLAY INVISIBLE (9300 -1150);
FORCEADD UNIVERSAL_GND..1
(10775 -3375);
FORCEPROP 3 LASTPIN (10775 -3325) SIG_NAME GND\g
J 0
(10785 -3315);
DISPLAY 0.659574 (10785 -3315);
PAINT MONO (10785 -3315);
DISPLAY INVISIBLE (10785 -3315);
FORCEPROP 2 LAST CDS_LIB pure_quanta_power
J 0
(10775 -3375);
DISPLAY INVISIBLE (10775 -3375);
FORCEPROP 1 LAST HDL_POWER GND
J 1
(10800 -3450);
DISPLAY 0.872340 (10800 -3450);
PAINT GREEN (10800 -3450);
DISPLAY INVISIBLE (10800 -3450);
FORCEPROP 1 LAST PATH I46
J 0
(10850 -3375);
DISPLAY 0.872340 (10850 -3375);
PAINT AQUA (10850 -3375);
DISPLAY INVISIBLE (10850 -3375);
FORCEADD Q_CAP..1
(10775 -3150);
FORCEPROP 1 LAST LOCATION C38
J 0
(10825 -3050);
DISPLAY 0.978723 (10825 -3050);
FORCEPROP 0 LAST $SEC 1
J 0
(10825 -3000);
DISPLAY 0.680851 (10825 -3000);
PAINT MONO (10825 -3000);
DISPLAY INVISIBLE (10825 -3000);
FORCEPROP 0 LAST CDS_SEC 1
J 0
(10825 -3000);
DISPLAY 1.021277 (10825 -3000);
DISPLAY INVISIBLE (10825 -3000);
FORCEPROP 1 LASTPIN (10775 -3050) $PN 1
J 0
(10785 -3070);
DISPLAY 0.787234 (10785 -3070);
PAINT MONO (10785 -3070);
FORCEPROP 1 LASTPIN (10775 -3250) $PN 2
J 0
(10785 -3270);
DISPLAY 0.787234 (10785 -3270);
PAINT MONO (10785 -3270);
FORCEPROP 1 LAST PACK_TYPE 0402
J 0
(10825 -3350);
DISPLAY 0.510638 (10825 -3350);
FORCEPROP 1 LAST MATERIAL X7R
J 0
(10825 -3250);
DISPLAY 0.510638 (10825 -3250);
FORCEPROP 1 LAST TOLERANCE 10%
J 0
(10825 -3200);
DISPLAY 0.510638 (10825 -3200);
FORCEPROP 1 LAST VOLTAGE 25V
J 0
(10825 -3150);
DISPLAY 0.510638 (10825 -3150);
FORCEPROP 1 LAST VALUE 0.1UF
J 0
(10825 -3100);
DISPLAY 0.510638 (10825 -3100);
FORCEPROP 2 LAST CDS_LIB pure_quanta
J 0
(10775 -3150);
DISPLAY INVISIBLE (10775 -3150);
FORCEPROP 1 LAST PATH I47
J 0
(10825 -3000);
DISPLAY 0.978723 (10825 -3000);
PAINT WHITE (10825 -3000);
DISPLAY INVISIBLE (10825 -3000);
FORCEPROP 1 LAST PART_NUMBER CH4104K1B00
J 0
(10825 -3300);
DISPLAY 0.510638 (10825 -3300);
DISPLAY INVISIBLE (10825 -3300);
FORCEADD OFFPAGE..1
R 2
(11200 -3475);
FORCEPROP 2 LAST $XR0 138 
J 0
(11386 -3475);
DISPLAY 0.638298 (11386 -3475);
PAINT MONO (11386 -3475);
FORCEPROP 2 LAST CDS_LIB standard
J 2
(11200 -3475);
DISPLAY INVISIBLE (11200 -3475);
FORCEPROP 1 LAST OFFPAGE TRUE
J 2
(10875 -3600);
DISPLAY 0.872340 (10875 -3600);
PAINT GREEN (10875 -3600);
DISPLAY INVISIBLE (10875 -3600);
FORCEPROP 1 LAST COMMENT_BODY TRUE
J 2
(11075 -3575);
DISPLAY 0.872340 (11075 -3575);
PAINT GREEN (11075 -3575);
DISPLAY INVISIBLE (11075 -3575);
FORCEPROP 2 LAST PATH I48
J 0
(11400 -3425);
DISPLAY 0.680851 (11400 -3425);
DISPLAY INVISIBLE (11400 -3425);
FORCEADD UNIVERSAL_POWER..1
(10575 -2875);
FORCEPROP 3 LASTPIN (10575 -2925) SIG_NAME P3V3_AUX\g
J 0
(10585 -2915);
DISPLAY 0.659574 (10585 -2915);
PAINT MONO (10585 -2915);
DISPLAY INVISIBLE (10585 -2915);
FORCEPROP 1 LAST HDL_POWER P3V3_AUX
J 1
(10575 -2825);
DISPLAY 0.872340 (10575 -2825);
PAINT GREEN (10575 -2825);
FORCEPROP 2 LAST CDS_LIB pure_quanta_power
J 0
(10575 -2875);
DISPLAY INVISIBLE (10575 -2875);
FORCEPROP 1 LAST PATH I49
J 0
(10625 -2850);
DISPLAY 0.872340 (10625 -2850);
PAINT AQUA (10625 -2850);
DISPLAY INVISIBLE (10625 -2850);
FORCEADD UNIVERSAL_POWER..1
(3625 -1025);
FORCEPROP 3 LASTPIN (3625 -1075) SIG_NAME P3V3_OCP_V3_2\g
J 0
(3635 -1065);
DISPLAY 0.659574 (3635 -1065);
PAINT MONO (3635 -1065);
DISPLAY INVISIBLE (3635 -1065);
FORCEPROP 1 LAST HDL_POWER P3V3_OCP_V3_2
J 1
(3625 -975);
DISPLAY 0.872340 (3625 -975);
PAINT GREEN (3625 -975);
FORCEPROP 2 LAST CDS_LIB pure_quanta_power
J 0
(3625 -1025);
PAINT MONO (3625 -1025);
DISPLAY INVISIBLE (3625 -1025);
FORCEPROP 1 LAST PATH I5
J 0
(3675 -1000);
DISPLAY 0.872340 (3675 -1000);
PAINT AQUA (3675 -1000);
DISPLAY INVISIBLE (3675 -1000);
FORCEADD OFFPAGE..2
(10750 -1825);
FORCEPROP 2 LAST $XR0 155 
J 0
(10939 -1825);
DISPLAY 0.638298 (10939 -1825);
PAINT MONO (10939 -1825);
FORCEPROP 2 LAST CDS_LIB standard
J 0
(10750 -1825);
PAINT MONO (10750 -1825);
DISPLAY INVISIBLE (10750 -1825);
FORCEPROP 1 LAST OFFPAGE TRUE
J 0
(11075 -1950);
DISPLAY 0.872340 (11075 -1950);
PAINT GREEN (11075 -1950);
DISPLAY INVISIBLE (11075 -1950);
FORCEPROP 1 LAST COMMENT_BODY TRUE
J 0
(10705 -1920);
DISPLAY 0.872340 (10705 -1920);
PAINT GREEN (10705 -1920);
DISPLAY INVISIBLE (10705 -1920);
FORCEPROP 2 LAST PATH I50
J 0
(11200 -1775);
DISPLAY 0.680851 (11200 -1775);
DISPLAY INVISIBLE (11200 -1775);
FORCEADD UNIVERSAL_POWER..1
(6250 250);
FORCEPROP 3 LASTPIN (6250 200) SIG_NAME P3V3_AUX\g
J 0
(6260 210);
DISPLAY 0.659574 (6260 210);
PAINT MONO (6260 210);
DISPLAY INVISIBLE (6260 210);
FORCEPROP 1 LAST HDL_POWER P3V3_AUX
J 1
(6250 300);
DISPLAY 0.872340 (6250 300);
PAINT GREEN (6250 300);
FORCEPROP 2 LAST CDS_LIB pure_quanta_power
J 0
(6250 250);
PAINT MONO (6250 250);
DISPLAY INVISIBLE (6250 250);
FORCEPROP 1 LAST PATH I51
J 0
(6300 275);
DISPLAY 0.872340 (6300 275);
PAINT AQUA (6300 275);
DISPLAY INVISIBLE (6300 275);
FORCEADD OFFPAGE..1
(3850 925);
FORCEPROP 2 LAST $XR0 142 
J 0
(3598 925);
DISPLAY 0.638298 (3598 925);
PAINT MONO (3598 925);
FORCEPROP 2 LAST CDS_LIB standard
J 0
(3850 925);
PAINT MONO (3850 925);
DISPLAY INVISIBLE (3850 925);
FORCEPROP 1 LAST OFFPAGE TRUE
J 0
(4175 800);
DISPLAY 0.872340 (4175 800);
PAINT GREEN (4175 800);
DISPLAY INVISIBLE (4175 800);
FORCEPROP 1 LAST COMMENT_BODY TRUE
J 0
(3975 825);
DISPLAY 0.872340 (3975 825);
PAINT GREEN (3975 825);
DISPLAY INVISIBLE (3975 825);
FORCEPROP 2 LAST PATH I53
J 0
(3600 975);
DISPLAY 0.680851 (3600 975);
DISPLAY INVISIBLE (3600 975);
FORCEADD UNIVERSAL_GND..1
(4500 1025);
FORCEPROP 3 LASTPIN (4500 1075) SIG_NAME GND\g
J 0
(4510 1085);
DISPLAY 0.659574 (4510 1085);
PAINT MONO (4510 1085);
DISPLAY INVISIBLE (4510 1085);
FORCEPROP 2 LAST CDS_LIB pure_quanta_power
J 0
(4500 1025);
PAINT MONO (4500 1025);
DISPLAY INVISIBLE (4500 1025);
FORCEPROP 1 LAST HDL_POWER GND
J 1
(4525 950);
DISPLAY 0.872340 (4525 950);
PAINT GREEN (4525 950);
DISPLAY INVISIBLE (4525 950);
FORCEPROP 1 LAST PATH I54
J 0
(4575 1025);
DISPLAY 0.872340 (4575 1025);
PAINT AQUA (4575 1025);
DISPLAY INVISIBLE (4575 1025);
FORCEADD Q_CAP..1
R 2
(4500 1250);
FORCEPROP 1 LAST LOCATION C1821
J 2
(4450 1350);
DISPLAY 0.978723 (4450 1350);
FORCEPROP 2 LAST $SEC 1
J 0
(4450 1450);
DISPLAY 0.680851 (4450 1450);
PAINT MONO (4450 1450);
DISPLAY INVISIBLE (4450 1450);
FORCEPROP 2 LAST CDS_SEC 1
J 0
(4450 1450);
DISPLAY 1.021277 (4450 1450);
DISPLAY INVISIBLE (4450 1450);
FORCEPROP 1 LASTPIN (4500 1350) $PN 1
J 2
(4490 1330);
DISPLAY 0.787234 (4490 1330);
FORCEPROP 1 LASTPIN (4500 1150) $PN 2
J 2
(4490 1130);
DISPLAY 0.787234 (4490 1130);
FORCEPROP 1 LAST VALUE 0.1UF
J 2
(4450 1300);
DISPLAY 0.510638 (4450 1300);
FORCEPROP 1 LAST VOLTAGE 25V
J 2
(4450 1250);
DISPLAY 0.510638 (4450 1250);
FORCEPROP 1 LAST TOLERANCE 10%
J 2
(4450 1200);
DISPLAY 0.510638 (4450 1200);
FORCEPROP 1 LAST PACK_TYPE 0402
J 2
(4450 1050);
DISPLAY 0.510638 (4450 1050);
FORCEPROP 1 LAST MATERIAL X7R
J 2
(4450 1150);
DISPLAY 0.510638 (4450 1150);
FORCEPROP 2 LAST CDS_LIB pure_quanta
J 0
(4500 1250);
PAINT MONO (4500 1250);
DISPLAY INVISIBLE (4500 1250);
FORCEPROP 1 LAST PATH I55
J 2
(4450 1400);
DISPLAY 0.978723 (4450 1400);
PAINT WHITE (4450 1400);
DISPLAY INVISIBLE (4450 1400);
FORCEPROP 1 LAST PART_NUMBER CH4104K1B00
J 2
(4450 1100);
DISPLAY 0.510638 (4450 1100);
DISPLAY INVISIBLE (4450 1100);
FORCEADD UNIVERSAL_GND..1
(4825 675);
FORCEPROP 3 LASTPIN (4825 725) SIG_NAME GND\g
J 0
(4835 735);
DISPLAY 0.659574 (4835 735);
PAINT MONO (4835 735);
DISPLAY INVISIBLE (4835 735);
FORCEPROP 2 LAST CDS_LIB pure_quanta_power
J 0
(4825 675);
PAINT MONO (4825 675);
DISPLAY INVISIBLE (4825 675);
FORCEPROP 1 LAST HDL_POWER GND
J 1
(4850 600);
DISPLAY 0.872340 (4850 600);
PAINT GREEN (4850 600);
DISPLAY INVISIBLE (4850 600);
FORCEPROP 1 LAST PATH I56
J 0
(4900 675);
DISPLAY 0.872340 (4900 675);
PAINT AQUA (4900 675);
DISPLAY INVISIBLE (4900 675);
FORCEADD UNIVERSAL_POWER..1
(4700 1525);
FORCEPROP 3 LASTPIN (4700 1475) SIG_NAME P3V3_AUX\g
J 0
(4710 1485);
DISPLAY 0.659574 (4710 1485);
PAINT MONO (4710 1485);
DISPLAY INVISIBLE (4710 1485);
FORCEPROP 1 LAST HDL_POWER P3V3_AUX
J 1
(4700 1575);
DISPLAY 0.872340 (4700 1575);
PAINT GREEN (4700 1575);
FORCEPROP 2 LAST CDS_LIB pure_quanta_power
J 0
(4700 1525);
PAINT MONO (4700 1525);
DISPLAY INVISIBLE (4700 1525);
FORCEPROP 1 LAST PATH I57
J 0
(4750 1550);
DISPLAY 0.872340 (4750 1550);
PAINT AQUA (4750 1550);
DISPLAY INVISIBLE (4750 1550);
FORCEADD 74LVC1G17GW..1
(5000 925);
FORCEPROP 1 LAST LOCATION U207
J 0
(4875 1200);
DISPLAY 0.723404 (4875 1200);
PAINT GREEN (4875 1200);
FORCEPROP 2 LAST SEC 1
J 0
(4900 1300);
DISPLAY 0.680851 (4900 1300);
PAINT MONO (4900 1300);
DISPLAY INVISIBLE (4900 1300);
FORCEPROP 2 LASTPIN (4825 925) $PN 2
J 2
(4815 935);
DISPLAY 0.680851 (4815 935);
PAINT MONO (4815 935);
FORCEPROP 2 LASTPIN (4825 825) $PN 3
J 2
(4815 835);
DISPLAY 0.680851 (4815 835);
PAINT MONO (4815 835);
FORCEPROP 2 LASTPIN (5175 825) $PN 1
J 0
(5185 835);
DISPLAY 0.680851 (5185 835);
PAINT MONO (5185 835);
FORCEPROP 2 LASTPIN (4825 1025) $PN 5
J 2
(4815 1035);
DISPLAY 0.680851 (4815 1035);
PAINT MONO (4815 1035);
FORCEPROP 2 LASTPIN (5175 925) $PN 4
J 0
(5185 935);
DISPLAY 0.680851 (5185 935);
PAINT MONO (5185 935);
FORCEPROP 2 LAST PART_TYPE SMLF
J 0
(4875 1300);
DISPLAY 0.638298 (4875 1300);
FORCEPROP 1 LAST MATERIAL IC
J 0
(4866 1079);
DISPLAY 0.723404 (4866 1079);
PAINT GREEN (4866 1079);
FORCEPROP 2 LAST VALUE 74LVC1G17GW
J 0
(4875 1250);
DISPLAY 0.638298 (4875 1250);
FORCEPROP 2 LAST SEC_TYPE 
J 0
(4900 1300);
DISPLAY 1.021277 (4900 1300);
DISPLAY INVISIBLE (4900 1300);
FORCEPROP 2 LAST CDS_LIB pure_quanta
J 0
(5000 925);
DISPLAY INVISIBLE (5000 925);
FORCEPROP 1 LAST CDS_LMAN_SYM_OUTLINE -125,150,125,-150
J 0
(5000 925);
DISPLAY 0.468085 (5000 925);
PAINT GREEN (5000 925);
DISPLAY INVISIBLE (5000 925);
FORCEPROP 1 LAST PIN_NAMES_ROTATE True
J 0
(5000 925);
DISPLAY 0.489362 (5000 925);
PAINT GREEN (5000 925);
DISPLAY INVISIBLE (5000 925);
FORCEPROP 1 LAST PATH I58
J 0
(5125 775);
DISPLAY 0.723404 (5125 775);
PAINT GREEN (5125 775);
DISPLAY INVISIBLE (5125 775);
FORCEPROP 1 LAST PART_NUMBER AL1G0017K01
J 0
(4866 1159);
DISPLAY 0.723404 (4866 1159);
PAINT GREEN (4866 1159);
DISPLAY INVISIBLE (4866 1159);
FORCEADD Q_RES..1
(4300 -3175);
FORCEPROP 1 LAST LOCATION R3234
J 0
(4050 -3175);
DISPLAY 0.638298 (4050 -3175);
FORCEPROP 2 LAST $SEC 1
J 0
(4250 -2975);
DISPLAY 0.680851 (4250 -2975);
PAINT MONO (4250 -2975);
DISPLAY INVISIBLE (4250 -2975);
FORCEPROP 2 LAST CDS_SEC 1
J 0
(4250 -2975);
DISPLAY 1.021277 (4250 -2975);
DISPLAY INVISIBLE (4250 -2975);
FORCEPROP 1 LASTPIN (4200 -3175) $PN 1
J 0
(4212 -3163);
DISPLAY 0.787234 (4212 -3163);
FORCEPROP 1 LASTPIN (4400 -3175) $PN 2
J 0
(4362 -3163);
DISPLAY 0.787234 (4362 -3163);
FORCEPROP 1 LAST PACK_TYPE 0402LF
J 0
(4200 -3250);
DISPLAY 0.510638 (4200 -3250);
FORCEPROP 1 LAST WATTAGE 1/16W
J 2
(4475 -3300);
DISPLAY 0.510638 (4475 -3300);
FORCEPROP 1 LAST MATERIAL CHIP
J 0
(4200 -3300);
DISPLAY 0.510638 (4200 -3300);
FORCEPROP 1 LAST VALUE 33.2
J 2
(4500 -3175);
DISPLAY 0.510638 (4500 -3175);
FORCEPROP 1 LAST TOLERANCE 1%
J 0
(4525 -3175);
DISPLAY 0.510638 (4525 -3175);
FORCEPROP 2 LAST CDS_LIB pure_quanta
J 0
(4300 -3175);
PAINT MONO (4300 -3175);
DISPLAY INVISIBLE (4300 -3175);
FORCEPROP 1 LAST PATH I6
J 0
(4250 -3025);
DISPLAY 0.978723 (4250 -3025);
PAINT WHITE (4250 -3025);
DISPLAY INVISIBLE (4250 -3025);
FORCEPROP 1 LAST PART_NUMBER CS03322FB03
J 0
(4200 -3350);
DISPLAY 0.510638 (4200 -3350);
DISPLAY INVISIBLE (4200 -3350);
FORCEADD OFFPAGE..2
(7250 775);
FORCEPROP 2 LAST $XR0 137 
J 0
(7439 775);
DISPLAY 0.638298 (7439 775);
PAINT MONO (7439 775);
FORCEPROP 2 LAST CDS_LIB standard
J 0
(7250 775);
DISPLAY INVISIBLE (7250 775);
FORCEPROP 1 LAST OFFPAGE TRUE
J 0
(7575 650);
DISPLAY 0.872340 (7575 650);
PAINT GREEN (7575 650);
DISPLAY INVISIBLE (7575 650);
FORCEPROP 1 LAST COMMENT_BODY TRUE
J 0
(7205 680);
DISPLAY 0.872340 (7205 680);
PAINT GREEN (7205 680);
DISPLAY INVISIBLE (7205 680);
FORCEPROP 2 LAST PATH I68
J 0
(7450 825);
DISPLAY 0.680851 (7450 825);
DISPLAY INVISIBLE (7450 825);
FORCEADD OFFPAGE..2
(7250 875);
FORCEPROP 2 LAST $XR0 137 
J 0
(7439 875);
DISPLAY 0.638298 (7439 875);
PAINT MONO (7439 875);
FORCEPROP 2 LAST CDS_LIB standard
J 0
(7250 875);
DISPLAY INVISIBLE (7250 875);
FORCEPROP 1 LAST OFFPAGE TRUE
J 0
(7575 750);
DISPLAY 0.872340 (7575 750);
PAINT GREEN (7575 750);
DISPLAY INVISIBLE (7575 750);
FORCEPROP 1 LAST COMMENT_BODY TRUE
J 0
(7205 780);
DISPLAY 0.872340 (7205 780);
PAINT GREEN (7205 780);
DISPLAY INVISIBLE (7205 780);
FORCEPROP 2 LAST PATH I69
J 0
(7450 925);
DISPLAY 0.680851 (7450 925);
DISPLAY INVISIBLE (7450 925);
FORCEADD OFFPAGE..1
(4500 -3075);
FORCEPROP 2 LAST $XR5 253 
J 0
(3679 -3075);
DISPLAY 0.638298 (3679 -3075);
PAINT MONO (3679 -3075);
FORCEPROP 2 LAST $XR4 251 
J 0
(3799 -3075);
DISPLAY 0.638298 (3799 -3075);
PAINT MONO (3799 -3075);
FORCEPROP 2 LAST $XR3 246 
J 0
(3919 -3075);
DISPLAY 0.638298 (3919 -3075);
PAINT MONO (3919 -3075);
FORCEPROP 2 LAST $XR2 241 
J 0
(4039 -3075);
DISPLAY 0.638298 (4039 -3075);
PAINT MONO (4039 -3075);
FORCEPROP 2 LAST $XR1 132 
J 0
(4159 -3075);
DISPLAY 0.638298 (4159 -3075);
PAINT MONO (4159 -3075);
FORCEPROP 2 LAST $XR0 80 
J 0
(4279 -3075);
DISPLAY 0.638298 (4279 -3075);
PAINT MONO (4279 -3075);
FORCEPROP 2 LAST CDS_LIB standard
J 0
(4500 -3075);
PAINT MONO (4500 -3075);
DISPLAY INVISIBLE (4500 -3075);
FORCEPROP 1 LAST OFFPAGE TRUE
J 0
(4825 -3200);
DISPLAY 0.872340 (4825 -3200);
PAINT GREEN (4825 -3200);
DISPLAY INVISIBLE (4825 -3200);
FORCEPROP 1 LAST COMMENT_BODY TRUE
J 0
(4625 -3175);
DISPLAY 0.872340 (4625 -3175);
PAINT GREEN (4625 -3175);
DISPLAY INVISIBLE (4625 -3175);
FORCEPROP 2 LAST PATH I7
J 0
(4225 -3025);
DISPLAY 0.680851 (4225 -3025);
DISPLAY INVISIBLE (4225 -3025);
FORCEADD OFFPAGE..2
(7250 925);
FORCEPROP 2 LAST $XR0 137 
J 0
(7439 925);
DISPLAY 0.638298 (7439 925);
PAINT MONO (7439 925);
FORCEPROP 2 LAST CDS_LIB standard
J 0
(7250 925);
DISPLAY INVISIBLE (7250 925);
FORCEPROP 1 LAST OFFPAGE TRUE
J 0
(7575 800);
DISPLAY 0.872340 (7575 800);
PAINT GREEN (7575 800);
DISPLAY INVISIBLE (7575 800);
FORCEPROP 1 LAST COMMENT_BODY TRUE
J 0
(7205 830);
DISPLAY 0.872340 (7205 830);
PAINT GREEN (7205 830);
DISPLAY INVISIBLE (7205 830);
FORCEPROP 2 LAST PATH I70
J 0
(7450 975);
DISPLAY 0.680851 (7450 975);
DISPLAY INVISIBLE (7450 975);
FORCEADD OFFPAGE..2
(7250 825);
FORCEPROP 2 LAST $XR0 137 
J 0
(7439 825);
DISPLAY 0.638298 (7439 825);
PAINT MONO (7439 825);
FORCEPROP 2 LAST CDS_LIB standard
J 0
(7250 825);
DISPLAY INVISIBLE (7250 825);
FORCEPROP 1 LAST OFFPAGE TRUE
J 0
(7575 700);
DISPLAY 0.872340 (7575 700);
PAINT GREEN (7575 700);
DISPLAY INVISIBLE (7575 700);
FORCEPROP 1 LAST COMMENT_BODY TRUE
J 0
(7205 730);
DISPLAY 0.872340 (7205 730);
PAINT GREEN (7205 730);
DISPLAY INVISIBLE (7205 730);
FORCEPROP 2 LAST PATH I71
J 0
(7450 875);
DISPLAY 0.680851 (7450 875);
DISPLAY INVISIBLE (7450 875);
FORCEADD Q_RES..1
(6475 925);
FORCEPROP 1 LAST LOCATION R6056
J 0
(6575 925);
DISPLAY 0.489362 (6575 925);
PAINT SKYBLUE (6575 925);
FORCEPROP 0 LAST $SEC 1
J 0
(6575 975);
DISPLAY 0.680851 (6575 975);
PAINT MONO (6575 975);
DISPLAY INVISIBLE (6575 975);
FORCEPROP 0 LAST CDS_SEC 1
J 0
(6575 975);
DISPLAY 0.680851 (6575 975);
DISPLAY INVISIBLE (6575 975);
FORCEPROP 1 LASTPIN (6375 925) $PN 1
J 0
(6387 937);
DISPLAY 0.489362 (6387 937);
PAINT MONO (6387 937);
FORCEPROP 1 LASTPIN (6575 925) $PN 2
J 0
(6537 937);
DISPLAY 0.489362 (6537 937);
PAINT MONO (6537 937);
FORCEPROP 1 LAST VALUE 0
J 2
(6350 925);
DISPLAY 0.489362 (6350 925);
PAINT SKYBLUE (6350 925);
FORCEPROP 2 LAST CDS_LIB pure_quanta
J 0
(6475 925);
DISPLAY INVISIBLE (6475 925);
FORCEPROP 2 LAST BOM_COST MEM
J 2
(6500 1075);
DISPLAY 0.744681 (6500 1075);
PAINT WHITE (6500 1075);
DISPLAY INVISIBLE (6500 1075);
FORCEPROP 1 LAST WATTAGE 1/16W
J 2
(6400 850);
DISPLAY 0.489362 (6400 850);
PAINT SKYBLUE (6400 850);
DISPLAY INVISIBLE (6400 850);
FORCEPROP 1 LAST MATERIAL CHIP
J 2
(6650 900);
DISPLAY 0.489362 (6650 900);
PAINT SKYBLUE (6650 900);
DISPLAY INVISIBLE (6650 900);
FORCEPROP 1 LAST TOLERANCE 5%
J 0
(6350 900);
DISPLAY 0.489362 (6350 900);
PAINT SKYBLUE (6350 900);
DISPLAY INVISIBLE (6350 900);
FORCEPROP 1 LAST PACK_TYPE 0402LF
J 2
(6650 850);
DISPLAY 0.489362 (6650 850);
PAINT SKYBLUE (6650 850);
DISPLAY INVISIBLE (6650 850);
FORCEPROP 1 LAST PATH I72
J 0
(6425 1075);
DISPLAY 0.978723 (6425 1075);
PAINT WHITE (6425 1075);
DISPLAY INVISIBLE (6425 1075);
FORCEPROP 1 LAST PART_NUMBER CS00002JB13
J 2
(6575 975);
DISPLAY 0.489362 (6575 975);
PAINT SKYBLUE (6575 975);
DISPLAY INVISIBLE (6575 975);
FORCEADD Q_RES..1
(6475 875);
FORCEPROP 1 LAST LOCATION R6057
J 0
(6575 875);
DISPLAY 0.489362 (6575 875);
PAINT SKYBLUE (6575 875);
FORCEPROP 0 LAST $SEC 1
J 0
(6575 925);
DISPLAY 0.680851 (6575 925);
PAINT MONO (6575 925);
DISPLAY INVISIBLE (6575 925);
FORCEPROP 0 LAST CDS_SEC 1
J 0
(6575 925);
DISPLAY 0.680851 (6575 925);
DISPLAY INVISIBLE (6575 925);
FORCEPROP 1 LASTPIN (6375 875) $PN 1
J 0
(6387 887);
DISPLAY 0.489362 (6387 887);
PAINT MONO (6387 887);
FORCEPROP 1 LASTPIN (6575 875) $PN 2
J 0
(6537 887);
DISPLAY 0.489362 (6537 887);
PAINT MONO (6537 887);
FORCEPROP 1 LAST VALUE 0
J 2
(6350 875);
DISPLAY 0.489362 (6350 875);
PAINT SKYBLUE (6350 875);
FORCEPROP 2 LAST CDS_LIB pure_quanta
J 0
(6475 875);
DISPLAY INVISIBLE (6475 875);
FORCEPROP 2 LAST BOM_COST MEM
J 2
(6500 1025);
DISPLAY 0.744681 (6500 1025);
PAINT WHITE (6500 1025);
DISPLAY INVISIBLE (6500 1025);
FORCEPROP 1 LAST WATTAGE 1/16W
J 2
(6400 800);
DISPLAY 0.489362 (6400 800);
PAINT SKYBLUE (6400 800);
DISPLAY INVISIBLE (6400 800);
FORCEPROP 1 LAST MATERIAL CHIP
J 2
(6650 850);
DISPLAY 0.489362 (6650 850);
PAINT SKYBLUE (6650 850);
DISPLAY INVISIBLE (6650 850);
FORCEPROP 1 LAST TOLERANCE 5%
J 0
(6350 850);
DISPLAY 0.489362 (6350 850);
PAINT SKYBLUE (6350 850);
DISPLAY INVISIBLE (6350 850);
FORCEPROP 1 LAST PACK_TYPE 0402LF
J 2
(6650 800);
DISPLAY 0.489362 (6650 800);
PAINT SKYBLUE (6650 800);
DISPLAY INVISIBLE (6650 800);
FORCEPROP 1 LAST PATH I73
J 0
(6425 1025);
DISPLAY 0.978723 (6425 1025);
PAINT WHITE (6425 1025);
DISPLAY INVISIBLE (6425 1025);
FORCEPROP 1 LAST PART_NUMBER CS00002JB13
J 2
(6575 925);
DISPLAY 0.489362 (6575 925);
PAINT SKYBLUE (6575 925);
DISPLAY INVISIBLE (6575 925);
FORCEADD Q_RES..1
(6475 825);
FORCEPROP 1 LAST LOCATION R6058
J 0
(6575 825);
DISPLAY 0.489362 (6575 825);
PAINT SKYBLUE (6575 825);
FORCEPROP 0 LAST $SEC 1
J 0
(6575 875);
DISPLAY 0.680851 (6575 875);
PAINT MONO (6575 875);
DISPLAY INVISIBLE (6575 875);
FORCEPROP 0 LAST CDS_SEC 1
J 0
(6575 875);
DISPLAY 0.680851 (6575 875);
DISPLAY INVISIBLE (6575 875);
FORCEPROP 1 LASTPIN (6375 825) $PN 1
J 0
(6387 837);
DISPLAY 0.489362 (6387 837);
PAINT MONO (6387 837);
FORCEPROP 1 LASTPIN (6575 825) $PN 2
J 0
(6537 837);
DISPLAY 0.489362 (6537 837);
PAINT MONO (6537 837);
FORCEPROP 1 LAST VALUE 0
J 2
(6350 825);
DISPLAY 0.489362 (6350 825);
PAINT SKYBLUE (6350 825);
FORCEPROP 2 LAST CDS_LIB pure_quanta
J 0
(6475 825);
DISPLAY INVISIBLE (6475 825);
FORCEPROP 2 LAST BOM_COST MEM
J 2
(6500 975);
DISPLAY 0.744681 (6500 975);
PAINT WHITE (6500 975);
DISPLAY INVISIBLE (6500 975);
FORCEPROP 1 LAST WATTAGE 1/16W
J 2
(6400 750);
DISPLAY 0.489362 (6400 750);
PAINT SKYBLUE (6400 750);
DISPLAY INVISIBLE (6400 750);
FORCEPROP 1 LAST MATERIAL CHIP
J 2
(6650 800);
DISPLAY 0.489362 (6650 800);
PAINT SKYBLUE (6650 800);
DISPLAY INVISIBLE (6650 800);
FORCEPROP 1 LAST TOLERANCE 5%
J 0
(6350 800);
DISPLAY 0.489362 (6350 800);
PAINT SKYBLUE (6350 800);
DISPLAY INVISIBLE (6350 800);
FORCEPROP 1 LAST PACK_TYPE 0402LF
J 2
(6650 750);
DISPLAY 0.489362 (6650 750);
PAINT SKYBLUE (6650 750);
DISPLAY INVISIBLE (6650 750);
FORCEPROP 1 LAST PATH I74
J 0
(6425 975);
DISPLAY 0.978723 (6425 975);
PAINT WHITE (6425 975);
DISPLAY INVISIBLE (6425 975);
FORCEPROP 1 LAST PART_NUMBER CS00002JB13
J 2
(6575 875);
DISPLAY 0.489362 (6575 875);
PAINT SKYBLUE (6575 875);
DISPLAY INVISIBLE (6575 875);
FORCEADD Q_RES..1
(6475 775);
FORCEPROP 1 LAST LOCATION R6059
J 0
(6575 775);
DISPLAY 0.489362 (6575 775);
PAINT SKYBLUE (6575 775);
FORCEPROP 0 LAST $SEC 1
J 0
(6575 825);
DISPLAY 0.680851 (6575 825);
PAINT MONO (6575 825);
DISPLAY INVISIBLE (6575 825);
FORCEPROP 0 LAST CDS_SEC 1
J 0
(6575 825);
DISPLAY 0.680851 (6575 825);
DISPLAY INVISIBLE (6575 825);
FORCEPROP 1 LASTPIN (6375 775) $PN 1
J 0
(6387 787);
DISPLAY 0.489362 (6387 787);
PAINT MONO (6387 787);
FORCEPROP 1 LASTPIN (6575 775) $PN 2
J 0
(6537 787);
DISPLAY 0.489362 (6537 787);
PAINT MONO (6537 787);
FORCEPROP 1 LAST VALUE 0
J 2
(6350 775);
DISPLAY 0.489362 (6350 775);
PAINT SKYBLUE (6350 775);
FORCEPROP 2 LAST CDS_LIB pure_quanta
J 0
(6475 775);
DISPLAY INVISIBLE (6475 775);
FORCEPROP 2 LAST BOM_COST MEM
J 2
(6500 925);
DISPLAY 0.744681 (6500 925);
PAINT WHITE (6500 925);
DISPLAY INVISIBLE (6500 925);
FORCEPROP 1 LAST WATTAGE 1/16W
J 2
(6400 700);
DISPLAY 0.489362 (6400 700);
PAINT SKYBLUE (6400 700);
DISPLAY INVISIBLE (6400 700);
FORCEPROP 1 LAST MATERIAL CHIP
J 2
(6650 750);
DISPLAY 0.489362 (6650 750);
PAINT SKYBLUE (6650 750);
DISPLAY INVISIBLE (6650 750);
FORCEPROP 1 LAST TOLERANCE 5%
J 0
(6350 750);
DISPLAY 0.489362 (6350 750);
PAINT SKYBLUE (6350 750);
DISPLAY INVISIBLE (6350 750);
FORCEPROP 1 LAST PACK_TYPE 0402LF
J 2
(6650 700);
DISPLAY 0.489362 (6650 700);
PAINT SKYBLUE (6650 700);
DISPLAY INVISIBLE (6650 700);
FORCEPROP 1 LAST PATH I75
J 0
(6425 925);
DISPLAY 0.978723 (6425 925);
PAINT WHITE (6425 925);
DISPLAY INVISIBLE (6425 925);
FORCEPROP 1 LAST PART_NUMBER CS00002JB13
J 2
(6575 825);
DISPLAY 0.489362 (6575 825);
PAINT SKYBLUE (6575 825);
DISPLAY INVISIBLE (6575 825);
FORCEADD 74LVC1G66GV..1
(10125 -3425);
FORCEPROP 1 LAST LOCATION U321
J 0
(9970 -3085);
DISPLAY 0.723404 (9970 -3085);
PAINT GREEN (9970 -3085);
FORCEPROP 2 LAST SEC 1
J 0
(9975 -2950);
DISPLAY 0.680851 (9975 -2950);
PAINT MONO (9975 -2950);
DISPLAY INVISIBLE (9975 -2950);
FORCEPROP 2 LASTPIN (10425 -3475) $PN 4
J 0
(10435 -3465);
DISPLAY 0.680851 (10435 -3465);
PAINT MONO (10435 -3465);
FORCEPROP 2 LASTPIN (9825 -3525) $PN 3
J 2
(9815 -3515);
DISPLAY 0.680851 (9815 -3515);
PAINT MONO (9815 -3515);
FORCEPROP 2 LASTPIN (10425 -3325) $PN 5
J 0
(10435 -3315);
DISPLAY 0.680851 (10435 -3315);
PAINT MONO (10435 -3315);
FORCEPROP 2 LASTPIN (9825 -3325) $PN 1
J 2
(9815 -3315);
DISPLAY 0.680851 (9815 -3315);
PAINT MONO (9815 -3315);
FORCEPROP 2 LASTPIN (9825 -3425) $PN 2
J 2
(9815 -3415);
DISPLAY 0.680851 (9815 -3415);
PAINT MONO (9815 -3415);
FORCEPROP 2 LAST PART_TYPE SMLF
J 0
(9975 -3000);
DISPLAY 0.680851 (9975 -3000);
FORCEPROP 1 LAST MATERIAL IC
J 0
(9970 -3270);
DISPLAY 0.723404 (9970 -3270);
PAINT GREEN (9970 -3270);
FORCEPROP 2 LAST VALUE 74LVC1G66GV
J 0
(9975 -3050);
DISPLAY 0.680851 (9975 -3050);
FORCEPROP 2 LAST SEC_TYPE 
J 0
(9975 -2950);
DISPLAY 0.680851 (9975 -2950);
DISPLAY INVISIBLE (9975 -2950);
FORCEPROP 2 LAST CDS_LIB pure_quanta
J 0
(10125 -3425);
DISPLAY INVISIBLE (10125 -3425);
FORCEPROP 1 LAST PIN_NAMES_ROTATE True
J 0
(10125 -3425);
DISPLAY 0.489362 (10125 -3425);
PAINT GREEN (10125 -3425);
DISPLAY INVISIBLE (10125 -3425);
FORCEPROP 1 LAST CDS_LMAN_SYM_OUTLINE -150,150,150,-150
J 0
(10125 -3425);
DISPLAY 0.468085 (10125 -3425);
PAINT GREEN (10125 -3425);
DISPLAY INVISIBLE (10125 -3425);
FORCEPROP 1 LAST PATH I76
J 0
(10275 -3575);
DISPLAY 0.723404 (10275 -3575);
PAINT GREEN (10275 -3575);
DISPLAY INVISIBLE (10275 -3575);
FORCEPROP 1 LAST PART_NUMBER AL001G66000
J 0
(9970 -3181);
DISPLAY 0.723404 (9970 -3181);
PAINT GREEN (9970 -3181);
DISPLAY INVISIBLE (9970 -3181);
FORCEADD UNIVERSAL_GND..1
(4850 -2175);
FORCEPROP 3 LASTPIN (4850 -2125) SIG_NAME GND\g
J 0
(4860 -2115);
DISPLAY 0.659574 (4860 -2115);
PAINT MONO (4860 -2115);
DISPLAY INVISIBLE (4860 -2115);
FORCEPROP 2 LAST CDS_LIB pure_quanta_power
J 0
(4850 -2175);
PAINT MONO (4850 -2175);
DISPLAY INVISIBLE (4850 -2175);
FORCEPROP 1 LAST HDL_POWER GND
J 1
(4875 -2250);
DISPLAY 0.872340 (4875 -2250);
PAINT GREEN (4875 -2250);
DISPLAY INVISIBLE (4875 -2250);
FORCEPROP 1 LAST PATH I8
J 0
(4925 -2175);
DISPLAY 0.872340 (4925 -2175);
PAINT AQUA (4925 -2175);
DISPLAY INVISIBLE (4925 -2175);
FORCEADD 74LVC1G126SE7..1
(5875 -3125);
FORCEPROP 1 LAST LOCATION U225
J 0
(5981 -3294);
DISPLAY 0.723404 (5981 -3294);
PAINT GREEN (5981 -3294);
FORCEPROP 0 LAST $SEC 1
J 0
(6000 -2900);
DISPLAY 0.680851 (6000 -2900);
PAINT MONO (6000 -2900);
DISPLAY INVISIBLE (6000 -2900);
FORCEPROP 0 LAST CDS_SEC 1
J 0
(6000 -2900);
DISPLAY 1.021277 (6000 -2900);
DISPLAY INVISIBLE (6000 -2900);
FORCEPROP 0 LASTPIN (5625 -3075) $PN 2
J 2
(5615 -3065);
DISPLAY 0.680851 (5615 -3065);
PAINT MONO (5615 -3065);
FORCEPROP 0 LASTPIN (5875 -3375) $PN 3
R 1
J 2
(5865 -3385);
DISPLAY 0.680851 (5865 -3385);
PAINT MONO (5865 -3385);
FORCEPROP 0 LASTPIN (5625 -3175) $PN 1
J 2
(5615 -3165);
DISPLAY 0.680851 (5615 -3165);
PAINT MONO (5615 -3165);
FORCEPROP 0 LASTPIN (5875 -2875) $PN 5
R 1
J 0
(5865 -2865);
DISPLAY 0.680851 (5865 -2865);
PAINT MONO (5865 -2865);
FORCEPROP 0 LASTPIN (6125 -3125) $PN 4
J 0
(6135 -3115);
DISPLAY 0.680851 (6135 -3115);
PAINT MONO (6135 -3115);
FORCEPROP 1 LAST MATERIAL IC
J 0
(5981 -3568);
DISPLAY 0.723404 (5981 -3568);
PAINT GREEN (5981 -3568);
FORCEPROP 2 LAST PART_TYPE SMLF
J 0
(6000 -2950);
DISPLAY 0.638298 (6000 -2950);
FORCEPROP 2 LAST VALUE 74LVC1G126SE-7
J 0
(6000 -3000);
DISPLAY 0.638298 (6000 -3000);
FORCEPROP 1 LAST CDS_LMAN_SYM_OUTLINE -100,100,100,-100
J 0
(5875 -3125);
DISPLAY 0.468085 (5875 -3125);
PAINT GREEN (5875 -3125);
DISPLAY INVISIBLE (5875 -3125);
FORCEPROP 2 LAST CDS_LIB pure_quanta
J 0
(5875 -3125);
DISPLAY INVISIBLE (5875 -3125);
FORCEPROP 1 LAST NEEDS_NO_SIZE TRUE
J 0
(5875 -3125);
DISPLAY 0.723404 (5875 -3125);
PAINT GREEN (5875 -3125);
DISPLAY INVISIBLE (5875 -3125);
FORCEPROP 1 LAST PATH I9
J 0
(5875 -3125);
DISPLAY 0.723404 (5875 -3125);
PAINT GREEN (5875 -3125);
DISPLAY INVISIBLE (5875 -3125);
FORCEPROP 1 LAST PART_NUMBER AL1G0126009
J 0
(5981 -3441);
DISPLAY 0.723404 (5981 -3441);
PAINT GREEN (5981 -3441);
DISPLAY INVISIBLE (5981 -3441);
FORCEADD CAD_NOTE..1
(9900 -1150);
FORCEPROP 0 LAST S1 PLACE R3192 CLOSE TO U219
J 0
(9750 -1300);
DISPLAY 0.808511 (9750 -1300);
PAINT SKYBLUE (9750 -1300);
FORCEPROP 2 LAST CDS_LIB pure_quanta_power
J 0
(9900 -1150);
DISPLAY INVISIBLE (9900 -1150);
FORCEPROP 1 LAST COMMENT_BODY TRUE
J 0
(9925 -1050);
DISPLAY 0.978723 (9925 -1050);
DISPLAY INVISIBLE (9925 -1050);
FORCEADD DNS..2
(9250 -1400);
PAINT RED (9250 -1400);
FORCEPROP 2 LAST CDS_LIB mstr_misc
J 0
(9250 -1400);
DISPLAY INVISIBLE (9250 -1400);
FORCEPROP 1 LAST COMMENT_BODY TRUE
R 1
J 0
(9325 -1625);
DISPLAY 0.872340 (9325 -1625);
PAINT GREEN (9325 -1625);
DISPLAY INVISIBLE (9325 -1625);
FORCEADD QUANTA_TITLE_BLOCK_C..1
(11700 -4550);
FORCEPROP 0 LAST CDS_CON_LAST_MODIFIED Thu Sep 14 16:12:26 2023
J 0
(9815 -4535);
DISPLAY INVISIBLE (9815 -4535);
FORCEPROP 1 LAST CUSTOM_TXT_CDS <CON_LAST_MODIFIED>
J 0
(9815 -4535);
DISPLAY 0.978723 (9815 -4535);
FORCEPROP 2 LAST CUSTOM_TXT_CDS <XR_PAGE_TITLE>
J 0
(3810 700);
DISPLAY 0.638298 (3810 700);
PAINT PINK (3810 700);
DISPLAY INVISIBLE (3810 700);
FORCEPROP 1 LAST CUSTOM_TXT_CDS <NAME_2>
J 0
(8525 -4500);
FORCEPROP 1 LAST CUSTOM_TXT_CDS <NAME_1>
J 0
(8525 -4375);
FORCEPROP 1 LAST CUSTOM_TXT_CDS <Q_NUMBER>
J 0
(10297 -4447);
DISPLAY 1.212766 (10297 -4447);
FORCEPROP 1 LAST CUSTOM_TXT_CDS <Q_PROJ>
J 0
(9318 -4448);
DISPLAY 1.212766 (9318 -4448);
FORCEPROP 1 LAST CUSTOM_TXT_CDS <Q_REV>
J 0
(11516 -4447);
DISPLAY 1.212766 (11516 -4447);
FORCEPROP 1 LAST CUSTOM_TXT_CDS <CON_PAGE_NUM> OF <CON_TOTAL_PAGES>
J 0
(11254 -4532);
DISPLAY 0.978723 (11254 -4532);
FORCEPROP 1 LAST Q_TITLE PCIE - V3_2 OCP3.0 (3/3)
J 0
(2334 -4524);
DISPLAY 2.446809 (2334 -4524);
PAINT GREEN (2334 -4524);
FORCEPROP 2 LAST PAGE_BORDER TRUE
J 0
(3810 700);
DISPLAY 0.638298 (3810 700);
PAINT PINK (3810 700);
DISPLAY INVISIBLE (3810 700);
FORCEPROP 1 LAST CDS_LMAN_SYM_OUTLINE -9475,6775,100,-125
J 0
(11700 -4550);
DISPLAY 0.468085 (11700 -4550);
PAINT GREEN (11700 -4550);
DISPLAY INVISIBLE (11700 -4550);
FORCEPROP 2 LAST CDS_LIB pure_quanta
J 0
(11700 -4550);
DISPLAY INVISIBLE (11700 -4550);
FORCEPROP 2 LAST CDS_XR_PAGE_TITLE CR-139 : @T6G_MB_LIB.T6G(SCH_1):PAGE139
J 0
(3810 700);
DISPLAY 0.638298 (3810 700);
PAINT PINK (3810 700);
DISPLAY INVISIBLE (3810 700);
FORCEPROP 1 LAST Q_DEPT BU9
J 1
(7937 -4501);
DISPLAY 1.957447 (7937 -4501);
PAINT GREEN (7937 -4501);
DISPLAY INVISIBLE (7937 -4501);
FORCEPROP 1 LAST COMMENT_BODY TRUE
J 0
(11712 -4563);
DISPLAY 0.978723 (11712 -4563);
PAINT GREEN (11712 -4563);
DISPLAY INVISIBLE (11712 -4563);
WIRE 16 -1 (5875 -3375)(5875 -3450);
WIRE 16 -1 (5650 -2800)(5650 -2875);
WIRE 16 -1 (5150 -1325)(5150 -1400);
WIRE 16 -1 (5975 -1175)(5975 -1125);
WIRE 16 -1 (5500 -500)(5300 -500);
WIRE 16 -1 (5300 -500)(5300 -675);
WIRE 16 -1 (6825 -3425)(6825 -3500);
WIRE 16 -1 (7800 -1825)(7600 -1825);
WIRE 16 -1 (7600 -1825)(7600 -2000);
WIRE 16 -1 (6450 -125)(6450 -200);
WIRE 16 -1 (7150 -25)(7150 25);
WIRE 16 -1 (9825 -3525)(9700 -3525);
WIRE 16 -1 (9700 -3525)(9700 -3625);
WIRE 16 -1 (8700 -1550)(8700 -1625);
WIRE 16 -1 (9250 -1275)(9250 -1225);
WIRE 16 -1 (10775 -3250)(10775 -3325);
WIRE 16 -1 (4500 1150)(4500 1075);
WIRE 16 -1 (4825 825)(4825 725);
WIRE 16 -1 (4850 -1975)(4850 -2125);
WIRE 16 -1 (4500 1425)(4700 1425);
WIRE 16 -1 (4500 1425)(4500 1350);
WIRE 16 -1 (4700 1025)(4700 1425);
WIRE 16 -1 (4700 1425)(4700 1475);
WIRE 16 -1 (4825 1025)(4700 1025);
WIRE 16 -1 (3900 925)(4825 925);
FORCEPROP 0 LAST CDS_PHYS_NET_NAME RST_HP_OCP_V3_2_N
J 0
(4265 967);
PAINT MONO (4265 967);
DISPLAY INVISIBLE (4265 967);
FORCEPROP 2 LAST SIG_NAME RST_PERST_OCP_V3_2_BUF_N
J 0
(3940 935);
DISPLAY 0.680851 (3940 935);
PAINT WHITE (3940 935);
WIRE 16 -1 (5175 925)(6200 925);
FORCEPROP 0 LAST CDS_PHYS_NET_NAME RST_OCP_V3_2_BUF_N
J 0
(5175 967);
PAINT MONO (5175 967);
DISPLAY INVISIBLE (5175 967);
FORCEPROP 0 LAST SIG_NAME RST_PERST_OCP_V3_2_BUF2_N
J 0
(5325 935);
DISPLAY 0.702128 (5325 935);
PAINT WHITE (5325 935);
FORCEPROP 2 LASTPROP $XRERR UNIQUE?
J 0
(5085 935);
DISPLAY 0.638298 (5085 935);
PAINT MONO (5085 935);
DISPLAY INVISIBLE (5085 935);
WIRE 16 -1 (6200 925)(6375 925);
WIRE 16 -1 (6200 925)(6200 875);
WIRE 16 -1 (6200 875)(6375 875);
WIRE 16 -1 (6200 875)(6200 825);
WIRE 16 -1 (6200 825)(6375 825);
WIRE 16 -1 (6200 825)(6200 775);
WIRE 16 -1 (6200 775)(6375 775);
WIRE 16 -1 (2875 -1675)(3350 -1675);
FORCEPROP 0 LAST CDS_PHYS_NET_NAME IRQ_LVC3_OCP_V3_2_WAKE_N
J 0
(3340 -1633);
PAINT MONO (3340 -1633);
DISPLAY INVISIBLE (3340 -1633);
WIRE 16 -1 (3350 -1675)(4600 -1675);
FORCEPROP 2 LAST SIG_NAME IRQ_LVC3_OCP_V3_2_WAKE_N
J 0
(3740 -1665);
DISPLAY 0.680851 (3740 -1665);
PAINT WHITE (3740 -1665);
WIRE 16 -1 (3350 -1475)(3350 -1675);
WIRE 16 -1 (3625 -1475)(3625 -1775);
WIRE 16 -1 (3625 -1775)(4600 -1775);
FORCEPROP 0 LAST CDS_PHYS_NET_NAME PU_OCP_V3_2_WAKE_OE
J 0
(3865 -1733);
PAINT MONO (3865 -1733);
DISPLAY INVISIBLE (3865 -1733);
FORCEPROP 2 LAST SIG_NAME PU_OCP_V3_2_WAKE_OE
J 0
(3740 -1765);
DISPLAY 0.680851 (3740 -1765);
PAINT WHITE (3740 -1765);
FORCEPROP 2 LASTPROP $XRERR UNIQUE?
J 0
(3500 -1765);
DISPLAY 0.638298 (3500 -1765);
PAINT MONO (3500 -1765);
DISPLAY INVISIBLE (3500 -1765);
WIRE 16 -1 (4200 -3175)(3125 -3175);
FORCEPROP 0 LAST CDS_PHYS_NET_NAME OCP_V3_2_AUX_PWR_EN
J 0
(3490 -3133);
PAINT MONO (3490 -3133);
DISPLAY INVISIBLE (3490 -3133);
FORCEPROP 2 LAST SIG_NAME OCP_V3_2_AUX_PWR_EN
J 0
(3215 -3165);
DISPLAY 0.680851 (3215 -3165);
PAINT WHITE (3215 -3165);
WIRE 16 -1 (4550 -3075)(5625 -3075);
FORCEPROP 0 LAST CDS_PHYS_NET_NAME RST_SMB_SWITCH_N
J 0
(4915 -3033);
PAINT MONO (4915 -3033);
DISPLAY INVISIBLE (4915 -3033);
FORCEPROP 2 LAST SIG_NAME RST_SMB_SWITCH_N
J 0
(4690 -3065);
DISPLAY 0.680851 (4690 -3065);
PAINT WHITE (4690 -3065);
WIRE 16 -1 (5625 -3175)(4400 -3175);
FORCEPROP 0 LAST CDS_PHYS_NET_NAME OCP_V3_2_AUX_PWR_EN_R3
J 0
(4765 -3133);
PAINT MONO (4765 -3133);
DISPLAY INVISIBLE (4765 -3133);
FORCEPROP 2 LAST SIG_NAME OCP_V3_2_AUX_PWR_EN_R3
J 0
(4690 -3165);
DISPLAY 0.680851 (4690 -3165);
PAINT WHITE (4690 -3165);
FORCEPROP 2 LASTPROP $XRERR UNIQUE?
J 0
(4450 -3165);
DISPLAY 0.638298 (4450 -3165);
PAINT MONO (4450 -3165);
DISPLAY INVISIBLE (4450 -3165);
WIRE 16 -1 (5500 -400)(4375 -400);
FORCEPROP 0 LAST CDS_PHYS_NET_NAME FM_SYS_THROTTLE_N
J 0
(4400 -358);
PAINT MONO (4400 -358);
DISPLAY INVISIBLE (4400 -358);
FORCEPROP 0 LAST SIG_NAME FM_SYS_THROTTLE_N
J 0
(4600 -390);
DISPLAY 0.702128 (4600 -390);
PAINT WHITE (4600 -390);
WIRE 16 -1 (5500 -300)(4375 -300);
FORCEPROP 0 LAST CDS_PHYS_NET_NAME NC_U218_NC1
J 0
(4400 -258);
PAINT MONO (4400 -258);
DISPLAY INVISIBLE (4400 -258);
FORCEPROP 0 LAST SIG_NAME NC_U218_NC1
J 0
(4590 -290);
DISPLAY 0.702128 (4590 -290);
PAINT WHITE (4590 -290);
FORCEPROP 2 LASTPROP $XRERR UNIQUE?
J 0
(4135 -300);
DISPLAY 0.638298 (4135 -300);
PAINT MONO (4135 -300);
DISPLAY INVISIBLE (4135 -300);
WIRE 16 -1 (5975 -1375)(5975 -1725);
WIRE 16 -1 (6200 -1725)(5975 -1725);
WIRE 16 -1 (5100 -1725)(5975 -1725);
FORCEPROP 0 LAST CDS_PHYS_NET_NAME OCP_V3_2_WAKE_BUFF_N
J 0
(5465 -1683);
PAINT MONO (5465 -1683);
DISPLAY INVISIBLE (5465 -1683);
FORCEPROP 2 LAST SIG_NAME OCP_V3_2_WAKE_BUFF_N
J 0
(5240 -1715);
DISPLAY 0.680851 (5240 -1715);
PAINT WHITE (5240 -1715);
FORCEPROP 2 LASTPROP $XRERR UNIQUE?
J 0
(5000 -1715);
DISPLAY 0.638298 (5000 -1715);
PAINT MONO (5000 -1715);
DISPLAY INVISIBLE (5000 -1715);
WIRE 16 -1 (6825 -3225)(6825 -3125);
WIRE 16 -1 (7000 -3125)(6825 -3125);
WIRE 16 -1 (6125 -3125)(6825 -3125);
FORCEPROP 2 LAST SIG_NAME RST_HP_OCP_V3_2_R_N
J 0
(6290 -3115);
DISPLAY 0.553191 (6290 -3115);
PAINT WHITE (6290 -3115);
FORCEPROP 2 LASTPROP $XRERR UNIQUE?
J 0
(6050 -3115);
DISPLAY 0.638298 (6050 -3115);
PAINT MONO (6050 -3115);
DISPLAY INVISIBLE (6050 -3115);
WIRE 16 -1 (8025 -3125)(7200 -3125);
FORCEPROP 2 LAST SIG_NAME RST_SMB_OCP_V3_2_N
J 0
(7515 -3115);
DISPLAY 0.553191 (7515 -3115);
PAINT WHITE (7515 -3115);
WIRE 16 -1 (8475 -3425)(7575 -3425);
FORCEPROP 0 LAST CDS_PHYS_NET_NAME CLK_50M_NCSI_OCP_V3_2_ISO
J 0
(7940 -3391);
PAINT MONO (7940 -3391);
DISPLAY INVISIBLE (7940 -3391);
FORCEPROP 2 LAST SIG_NAME CLK_50M_NCSI_OCP_V3_2_ISO
J 0
(7615 -3415);
DISPLAY 0.510638 (7615 -3415);
PAINT WHITE (7615 -3415);
WIRE 16 -1 (7600 -500)(7150 -500);
WIRE 16 -1 (7150 -225)(7150 -500);
WIRE 16 -1 (7150 -500)(6050 -500);
FORCEPROP 0 LAST CDS_PHYS_NET_NAME OCP_V3_2_PWRBRK_BUFF_N
J 0
(6565 -458);
PAINT MONO (6565 -458);
DISPLAY INVISIBLE (6565 -458);
FORCEPROP 2 LAST SIG_NAME OCP_V3_2_PWRBRK_BUFF_N
J 0
(6315 -490);
DISPLAY 0.680851 (6315 -490);
PAINT WHITE (6315 -490);
FORCEPROP 2 LASTPROP $XRERR UNIQUE?
J 0
(6075 -490);
DISPLAY 0.638298 (6075 -490);
PAINT MONO (6075 -490);
DISPLAY INVISIBLE (6075 -490);
WIRE 16 -1 (9650 -1825)(10700 -1825);
FORCEPROP 0 LAST CDS_PHYS_NET_NAME IRQ_LVC3_WAKE_N
J 0
(9675 -1783);
PAINT MONO (9675 -1783);
DISPLAY INVISIBLE (9675 -1783);
FORCEPROP 0 LAST SIG_NAME IRQ_OCP_V3_2_WAKE_BUF_N
J 0
(10015 -1815);
DISPLAY 0.553191 (10015 -1815);
PAINT WHITE (10015 -1815);
WIRE 16 -1 (9250 -1475)(9250 -1825);
WIRE 16 -1 (9250 -1825)(9450 -1825);
WIRE 16 -1 (8350 -1825)(9250 -1825);
FORCEPROP 0 LAST CDS_PHYS_NET_NAME IRQ_LVC3_V3_2_WAKE_BUF_N
J 0
(8375 -1783);
PAINT MONO (8375 -1783);
DISPLAY INVISIBLE (8375 -1783);
FORCEPROP 0 LAST SIG_NAME IRQ_LVC3_V3_2_WAKE_BUF_N
J 0
(8440 -1815);
DISPLAY 0.702128 (8440 -1815);
PAINT WHITE (8440 -1815);
FORCEPROP 2 LASTPROP $XRERR UNIQUE?
J 0
(8200 -1815);
DISPLAY 0.638298 (8200 -1815);
PAINT MONO (8200 -1815);
DISPLAY INVISIBLE (8200 -1815);
WIRE 16 -1 (8900 -500)(7800 -500);
FORCEPROP 0 LAST CDS_PHYS_NET_NAME OCP_V3_2_PWRBRK_N
J 0
(8340 -458);
PAINT MONO (8340 -458);
DISPLAY INVISIBLE (8340 -458);
FORCEPROP 2 LAST SIG_NAME OCP_V3_2_PWRBRK_N
J 0
(8215 -490);
DISPLAY 0.680851 (8215 -490);
PAINT WHITE (8215 -490);
WIRE 16 -1 (7800 -1625)(7125 -1625);
FORCEPROP 0 LAST CDS_PHYS_NET_NAME NC_U219_NC1
J 0
(7150 -1583);
PAINT MONO (7150 -1583);
DISPLAY INVISIBLE (7150 -1583);
FORCEPROP 0 LAST SIG_NAME NC_U219_NC1
J 0
(7240 -1615);
DISPLAY 0.702128 (7240 -1615);
PAINT WHITE (7240 -1615);
FORCEPROP 2 LASTPROP $XRERR UNIQUE?
J 0
(6885 -1625);
DISPLAY 0.638298 (6885 -1625);
PAINT MONO (6885 -1625);
DISPLAY INVISIBLE (6885 -1625);
WIRE 16 -1 (7800 -1725)(6400 -1725);
FORCEPROP 0 LAST CDS_PHYS_NET_NAME OCP_V3_2_WAKE_BUFF_R_N
J 0
(7065 -1683);
PAINT MONO (7065 -1683);
DISPLAY INVISIBLE (7065 -1683);
FORCEPROP 2 LAST SIG_NAME OCP_V3_2_WAKE_BUFF_R_N
J 0
(6890 -1715);
DISPLAY 0.680851 (6890 -1715);
PAINT WHITE (6890 -1715);
FORCEPROP 2 LASTPROP $XRERR UNIQUE?
J 0
(6650 -1715);
DISPLAY 0.638298 (6650 -1715);
PAINT MONO (6650 -1715);
DISPLAY INVISIBLE (6650 -1715);
WIRE 16 -1 (6575 925)(7200 925);
FORCEPROP 2 LAST SIG_NAME RST_PERST0_OCP_V3_2_N
J 0
(6740 935);
DISPLAY 0.489362 (6740 935);
WIRE 16 -1 (6575 875)(7200 875);
FORCEPROP 2 LAST SIG_NAME RST_PERST1_OCP_V3_2_N
J 0
(6740 885);
DISPLAY 0.489362 (6740 885);
WIRE 16 -1 (6575 825)(7200 825);
FORCEPROP 2 LAST SIG_NAME RST_PERST2_OCP_V3_2_N
J 0
(6740 835);
DISPLAY 0.489362 (6740 835);
WIRE 16 -1 (6575 775)(7200 775);
FORCEPROP 2 LAST SIG_NAME RST_PERST3_OCP_V3_2_N
J 0
(6740 785);
DISPLAY 0.489362 (6740 785);
WIRE 16 -1 (6050 -300)(6250 -300);
WIRE 16 -1 (6250 150)(6250 -300);
WIRE 16 -1 (6250 150)(6450 150);
WIRE 16 -1 (6250 200)(6250 150);
WIRE 16 -1 (6450 150)(6450 75);
WIRE 16 -1 (3350 -1275)(3350 -1150);
WIRE 16 -1 (3350 -1150)(3625 -1150);
WIRE 16 -1 (3625 -1150)(3625 -1075);
WIRE 16 -1 (3625 -1275)(3625 -1150);
WIRE 16 -1 (8500 -1275)(8700 -1275);
WIRE 16 -1 (8500 -1225)(8500 -1275);
WIRE 16 -1 (8500 -1275)(8500 -1625);
WIRE 16 -1 (8700 -1275)(8700 -1350);
WIRE 16 -1 (8350 -1625)(8500 -1625);
WIRE 16 -1 (4850 -1475)(4850 -1025);
FORCEPROP 0 LAST VOLTAGE 3.3
J 0
(4950 -1475);
PAINT MONO (4950 -1475);
DISPLAY INVISIBLE (4950 -1475);
FORCEPROP 0 LAST CDS_PHYS_NET_NAME P3V3_AUX
J 0
(4950 -1428);
PAINT MONO (4950 -1428);
DISPLAY INVISIBLE (4950 -1428);
FORCEPROP 0 LAST $PHYS_NET_NAME P3V3_AUX
J 0
(4950 -1381);
PAINT MONO (4950 -1381);
DISPLAY INVISIBLE (4950 -1381);
WIRE 16 -1 (4850 -1025)(5150 -1025);
WIRE 16 -1 (5150 -1025)(5150 -950);
WIRE 16 -1 (5150 -1125)(5150 -1025);
WIRE 16 -1 (5875 -2875)(5875 -2525);
WIRE 16 -1 (5875 -2525)(5650 -2525);
WIRE 16 -1 (5650 -2525)(5650 -2450);
WIRE 16 -1 (5650 -2525)(5650 -2600);
WIRE 16 -1 (9825 -3325)(8775 -3325);
FORCEPROP 0 LAST CDS_PHYS_NET_NAME CLK_50M_NCSI_OCP_V3_2
J 0
(9140 -3291);
PAINT MONO (9140 -3291);
DISPLAY INVISIBLE (9140 -3291);
FORCEPROP 2 LAST SIG_NAME CLK_50M_NCSI_OCP_V3_2
J 0
(8940 -3315);
DISPLAY 0.510638 (8940 -3315);
PAINT WHITE (8940 -3315);
WIRE 16 -1 (11150 -3475)(10425 -3475);
FORCEPROP 2 LAST SIG_NAME FB_BMC_ISOLATE1
J 0
(10615 -3465);
DISPLAY 0.553191 (10615 -3465);
PAINT WHITE (10615 -3465);
WIRE 16 -1 (10775 -2975)(10775 -3050);
WIRE 16 -1 (10575 -2975)(10775 -2975);
WIRE 16 -1 (10575 -2925)(10575 -2975);
WIRE 16 -1 (10575 -2975)(10575 -3325);
WIRE 16 -1 (10425 -3325)(10575 -3325);
WIRE 16 2175 (8275 -3375)(8925 -3375);
WIRE 16 2175 (8275 -3375)(8275 -3500);
WIRE 16 2175 (8925 -3375)(8925 -3500);
WIRE 16 2175 (8275 -3500)(8925 -3500);
WIRE 16 -1 (9825 -3425)(8675 -3425);
FORCEPROP 0 LAST CDS_PHYS_NET_NAME CLK_50M_NCSI_OCP_V3_2_ISO_R
J 0
(9040 -3391);
PAINT MONO (9040 -3391);
DISPLAY INVISIBLE (9040 -3391);
FORCEPROP 2 LAST SIG_NAME CLK_50M_NCSI_OCP_V3_2_ISO_R
J 0
(8940 -3415);
DISPLAY 0.510638 (8940 -3415);
PAINT WHITE (8940 -3415);
FORCEPROP 2 LASTPROP $XRERR UNIQUE?
J 0
(8700 -3415);
DISPLAY 0.638298 (8700 -3415);
PAINT MONO (8700 -3415);
DISPLAY INVISIBLE (8700 -3415);
CIRCLE (7450 0)(7610 0);
PAINT YELLOW (7450 0);
DOT 1 (3350 -1675);
DOT 1 (3625 -1150);
DOT 1 (5650 -2525);
DOT 1 (5150 -1025);
DOT 1 (5975 -1725);
DOT 1 (6825 -3125);
DOT 1 (7150 -500);
DOT 1 (8500 -1275);
DOT 1 (9250 -1825);
DOT 1 (10575 -2975);
DOT 1 (6250 150);
DOT 1 (4700 1425);
DOT 1 (6200 925);
DOT 1 (6200 875);
DOT 1 (6200 825);
FORCENOTE
20220120 ADD R4602
(8050 -3600) 0;
DISPLAY LEFT (8050 -3600);
DISPLAY 1.276596 (8050 -3600);
PAINT PINK (8050 -3600);
FORCENOTE
POP
(7425 -25) 0;
DISPLAY LEFT (7425 -25);
DISPLAY 1.021277 (7425 -25);
FORCENOTE
RST FOR OCP V3_2
(6725 1325) 0;
DISPLAY LEFT (6725 1325);
DISPLAY 1.021277 (6725 1325);
QUIT
